FILE_TYPE = MACRO_DRAWING;
SET COLOR_WIRE YELLOW;
SET COLOR_PROP MONO;
SET COLOR_DOT WHITE;
SET COLOR_ARC YELLOW;
SET COLOR_BODY GREEN;
SET COLOR_NOTE MONO;
SET PROP_DISPLAY VALUE;
SET PAGE_NUMBER P220;
FORCEADD PVDDQ_DEF..1
(2675 1950);
FORCEPROP 3 LASTPIN (2675 1900) SIG_NAME PVDDQ_DEF\g
J 0
(2685 1910);
DISPLAY 0.659574 (2685 1910);
PAINT MONO (2685 1910);
DISPLAY INVISIBLE (2685 1910);
FORCEPROP 2 LAST ROOM VDDQ_DEF_PWR_VR
J 0
(2925 2050);
PAINT ORANGE (2925 2050);
DISPLAY INVISIBLE (2925 2050);
FORCEPROP 2 LAST BOM_COST MEM_VRD_PVDDQ_DEF
J 0
(2750 2050);
PAINT MONO (2750 2050);
DISPLAY INVISIBLE (2750 2050);
FORCEPROP 1 LAST PATH I109
J 0
(2725 1975);
DISPLAY 0.872340 (2725 1975);
PAINT AQUA (2725 1975);
DISPLAY INVISIBLE (2725 1975);
FORCEPROP 2 LAST CDS_LIB mstr_symbols
J 0
(2675 1950);
PAINT ORANGE (2675 1950);
DISPLAY INVISIBLE (2675 1950);
FORCEPROP 1 LAST VOLTAGE 1.2V
J 0
(2630 1907);
DISPLAY 0.340426 (2630 1907);
PAINT SKYBLUE (2630 1907);
DISPLAY INVISIBLE (2630 1907);
FORCEPROP 1 LAST BODY_TYPE PLUMBING
J 0
(2630 1907);
DISPLAY 0.340426 (2630 1907);
PAINT GREEN (2630 1907);
DISPLAY INVISIBLE (2630 1907);
FORCEPROP 1 LAST HDL_POWER PVDDQ_DEF
J 1
(2675 2000);
DISPLAY 0.872340 (2675 2000);
PAINT GREEN (2675 2000);
DISPLAY INVISIBLE (2675 2000);
FORCEADD GND..1
(4400 1300);
FORCEPROP 3 LASTPIN (4400 1350) SIG_NAME GND\g
J 0
(4410 1360);
DISPLAY 0.659574 (4410 1360);
PAINT MONO (4410 1360);
DISPLAY INVISIBLE (4410 1360);
FORCEPROP 1 LAST VOLTAGE 0
J 0
(4400 1300);
PAINT SKYBLUE (4400 1300);
DISPLAY INVISIBLE (4400 1300);
FORCEPROP 2 LAST CDS_LIB mstr_symbols
J 0
(4400 1300);
PAINT ORANGE (4400 1300);
DISPLAY INVISIBLE (4400 1300);
FORCEPROP 1 LAST PATH I114
J 0
(4475 1300);
DISPLAY 1.170213 (4475 1300);
PAINT AQUA (4475 1300);
DISPLAY INVISIBLE (4475 1300);
FORCEPROP 1 LAST SIZE 1B
J 0
(4475 1250);
DISPLAY 0.893617 (4475 1250);
PAINT GREEN (4475 1250);
DISPLAY INVISIBLE (4475 1250);
FORCEPROP 2 LAST ROOM VDDQ_DEF_PWR_VR
J 0
(3850 1375);
PAINT ORANGE (3850 1375);
DISPLAY INVISIBLE (3850 1375);
FORCEPROP 2 LAST BOM_COST MEM_VRD_PVDDQ_DEF
J 0
(4075 1375);
PAINT MONO (4075 1375);
DISPLAY INVISIBLE (4075 1375);
FORCEPROP 1 LAST BODY_TYPE PLUMBING
J 0
(4355 1257);
DISPLAY 0.340426 (4355 1257);
PAINT GREEN (4355 1257);
DISPLAY INVISIBLE (4355 1257);
FORCEPROP 1 LAST HDL_POWER GND
J 0
(4400 1450);
DISPLAY 0.893617 (4400 1450);
PAINT GREEN (4400 1450);
DISPLAY INVISIBLE (4400 1450);
FORCEADD VCC_CORE..1
(1900 1500);
FORCEPROP 3 LASTPIN (1900 1450) SIG_NAME VR_FET_SW_P12V_STBY_PVDDQ_DEF\g
J 0
(1910 1460);
DISPLAY 0.659574 (1910 1460);
PAINT MONO (1910 1460);
DISPLAY INVISIBLE (1910 1460);
FORCEPROP 1 LAST HDL_POWER VR_FET_SW_P12V_STBY_PVDDQ_DEF
J 1
(1900 1550);
DISPLAY 0.617021 (1900 1550);
PAINT GREEN (1900 1550);
FORCEPROP 1 LAST PATH I120
J 0
(1950 1525);
DISPLAY 1.170213 (1950 1525);
PAINT AQUA (1950 1525);
DISPLAY INVISIBLE (1950 1525);
FORCEPROP 2 LAST CDS_LIB mstr_symbols
J 0
(1900 1500);
PAINT ORANGE (1900 1500);
DISPLAY INVISIBLE (1900 1500);
FORCEADD P12V_STBY..1
(-2250 1425);
FORCEPROP 3 LASTPIN (-2250 1375) SIG_NAME P12V_STBY\g
J 0
(-2240 1385);
DISPLAY 0.659574 (-2240 1385);
PAINT MONO (-2240 1385);
DISPLAY INVISIBLE (-2240 1385);
FORCEPROP 1 LAST HDL_POWER P12V_STBY
J 0
(-2550 1300);
DISPLAY 0.872340 (-2550 1300);
PAINT ORANGE (-2550 1300);
DISPLAY INVISIBLE (-2550 1300);
FORCEPROP 1 LAST BODY_TYPE PLUMBING
J 0
(-2295 1382);
DISPLAY 0.340426 (-2295 1382);
PAINT GREEN (-2295 1382);
DISPLAY INVISIBLE (-2295 1382);
FORCEPROP 1 LAST PATH I176
J 0
(-2205 1427);
DISPLAY 0.340426 (-2205 1427);
PAINT GREEN (-2205 1427);
DISPLAY INVISIBLE (-2205 1427);
FORCEPROP 2 LAST CDS_LIB mstr_symbols
J 0
(-2250 1425);
PAINT ORANGE (-2250 1425);
DISPLAY INVISIBLE (-2250 1425);
FORCEPROP 1 LAST SIZE 1B
J 0
(-2205 1447);
DISPLAY 0.340426 (-2205 1447);
PAINT GREEN (-2205 1447);
DISPLAY INVISIBLE (-2205 1447);
FORCEPROP 1 LAST VOLTAGE 12.0V
J 0
(-2295 1382);
DISPLAY 0.340426 (-2295 1382);
PAINT SKYBLUE (-2295 1382);
DISPLAY INVISIBLE (-2295 1382);
FORCEADD GND..1
(-400 2625);
FORCEPROP 3 LASTPIN (-400 2675) SIG_NAME GND\g
J 0
(-390 2685);
DISPLAY 0.659574 (-390 2685);
PAINT MONO (-390 2685);
DISPLAY INVISIBLE (-390 2685);
FORCEPROP 1 LAST HDL_POWER GND
J 0
(-400 2775);
DISPLAY 0.893617 (-400 2775);
PAINT GREEN (-400 2775);
DISPLAY INVISIBLE (-400 2775);
FORCEPROP 1 LAST BODY_TYPE PLUMBING
J 0
(-445 2582);
DISPLAY 0.340426 (-445 2582);
PAINT GREEN (-445 2582);
DISPLAY INVISIBLE (-445 2582);
FORCEPROP 2 LAST ROOM VDDQ_ABC_PWR_VR
J 0
(-950 2700);
PAINT ORANGE (-950 2700);
DISPLAY INVISIBLE (-950 2700);
FORCEPROP 2 LAST BOM_COST MEM_VRD_PVDDQ_CD
J 0
(-725 2700);
PAINT MONO (-725 2700);
DISPLAY INVISIBLE (-725 2700);
FORCEPROP 1 LAST SIZE 1B
J 0
(-325 2575);
DISPLAY 0.893617 (-325 2575);
PAINT GREEN (-325 2575);
DISPLAY INVISIBLE (-325 2575);
FORCEPROP 1 LAST PATH I181
J 0
(-325 2625);
DISPLAY 0.872340 (-325 2625);
PAINT AQUA (-325 2625);
DISPLAY INVISIBLE (-325 2625);
FORCEPROP 2 LAST CDS_LIB mstr_symbols
J 0
(-400 2625);
PAINT ORANGE (-400 2625);
DISPLAY INVISIBLE (-400 2625);
FORCEPROP 1 LAST VOLTAGE 0
J 0
(-400 2625);
PAINT SKYBLUE (-400 2625);
DISPLAY INVISIBLE (-400 2625);
FORCEADD PVDDQ_DEF..1
(-2300 3250);
FORCEPROP 3 LASTPIN (-2300 3200) SIG_NAME PVDDQ_DEF\g
J 0
(-2290 3210);
DISPLAY 0.659574 (-2290 3210);
PAINT MONO (-2290 3210);
DISPLAY INVISIBLE (-2290 3210);
FORCEPROP 1 LAST HDL_POWER PVDDQ_DEF
J 1
(-2300 3300);
DISPLAY 0.872340 (-2300 3300);
PAINT GREEN (-2300 3300);
DISPLAY INVISIBLE (-2300 3300);
FORCEPROP 1 LAST BODY_TYPE PLUMBING
J 0
(-2345 3207);
DISPLAY 0.340426 (-2345 3207);
PAINT GREEN (-2345 3207);
DISPLAY INVISIBLE (-2345 3207);
FORCEPROP 1 LAST VOLTAGE 1.2V
J 0
(-2345 3207);
DISPLAY 0.340426 (-2345 3207);
PAINT SKYBLUE (-2345 3207);
DISPLAY INVISIBLE (-2345 3207);
FORCEPROP 2 LAST CDS_LIB mstr_symbols
J 0
(-2300 3250);
PAINT ORANGE (-2300 3250);
DISPLAY INVISIBLE (-2300 3250);
FORCEPROP 2 LAST BOM_COST MEM_VRD_PVPP_DEF
J 0
(-2250 3350);
PAINT MONO (-2250 3350);
DISPLAY INVISIBLE (-2250 3350);
FORCEPROP 1 LAST PATH I185
J 0
(-2250 3275);
DISPLAY 0.872340 (-2250 3275);
PAINT AQUA (-2250 3275);
DISPLAY INVISIBLE (-2250 3275);
FORCEPROP 2 LAST ROOM VDDQ_DEF_PWR_VR
J 0
(-2075 3350);
PAINT ORANGE (-2075 3350);
DISPLAY INVISIBLE (-2075 3350);
FORCEADD PVDDQ_DEF..1
(2650 1225);
FORCEPROP 3 LASTPIN (2650 1175) SIG_NAME PVDDQ_DEF\g
J 0
(2660 1185);
DISPLAY 0.659574 (2660 1185);
PAINT MONO (2660 1185);
DISPLAY INVISIBLE (2660 1185);
FORCEPROP 2 LAST ROOM VDDQ_DEF_PWR_VR
J 0
(2900 1325);
PAINT ORANGE (2900 1325);
DISPLAY INVISIBLE (2900 1325);
FORCEPROP 2 LAST BOM_COST MEM_VRD_PVDDQ_DEF
J 0
(2725 1325);
PAINT MONO (2725 1325);
DISPLAY INVISIBLE (2725 1325);
FORCEPROP 1 LAST PATH I189
J 0
(2700 1250);
DISPLAY 0.872340 (2700 1250);
PAINT AQUA (2700 1250);
DISPLAY INVISIBLE (2700 1250);
FORCEPROP 1 LAST VOLTAGE 1.2V
J 0
(2605 1182);
DISPLAY 0.340426 (2605 1182);
PAINT SKYBLUE (2605 1182);
DISPLAY INVISIBLE (2605 1182);
FORCEPROP 2 LAST CDS_LIB mstr_symbols
J 0
(2650 1225);
PAINT ORANGE (2650 1225);
DISPLAY INVISIBLE (2650 1225);
FORCEPROP 1 LAST BODY_TYPE PLUMBING
J 0
(2605 1182);
DISPLAY 0.340426 (2605 1182);
PAINT GREEN (2605 1182);
DISPLAY INVISIBLE (2605 1182);
FORCEPROP 1 LAST HDL_POWER PVDDQ_DEF
J 1
(2650 1275);
DISPLAY 0.872340 (2650 1275);
PAINT GREEN (2650 1275);
DISPLAY INVISIBLE (2650 1275);
FORCEADD GND..1
(3600 600);
FORCEPROP 3 LASTPIN (3600 650) SIG_NAME GND\g
J 0
(3610 660);
DISPLAY 0.659574 (3610 660);
PAINT MONO (3610 660);
DISPLAY INVISIBLE (3610 660);
FORCEPROP 1 LAST PATH I191
J 0
(3675 600);
DISPLAY 0.872340 (3675 600);
PAINT AQUA (3675 600);
DISPLAY INVISIBLE (3675 600);
FORCEPROP 2 LAST CDS_LIB mstr_symbols
J 0
(3600 600);
PAINT ORANGE (3600 600);
DISPLAY INVISIBLE (3600 600);
FORCEPROP 1 LAST SIZE 1B
J 0
(3675 550);
DISPLAY 0.893617 (3675 550);
PAINT GREEN (3675 550);
DISPLAY INVISIBLE (3675 550);
FORCEPROP 1 LAST VOLTAGE 0
J 0
(3600 600);
PAINT SKYBLUE (3600 600);
DISPLAY INVISIBLE (3600 600);
FORCEPROP 2 LAST BOM_COST MEM_VRD_PVDDQ_DEF
J 0
(3275 675);
PAINT MONO (3275 675);
DISPLAY INVISIBLE (3275 675);
FORCEPROP 2 LAST ROOM VDDQ_DEF_PWR_VR
J 0
(3050 675);
PAINT ORANGE (3050 675);
DISPLAY INVISIBLE (3050 675);
FORCEPROP 1 LAST BODY_TYPE PLUMBING
J 0
(3555 557);
DISPLAY 0.340426 (3555 557);
PAINT GREEN (3555 557);
DISPLAY INVISIBLE (3555 557);
FORCEPROP 1 LAST HDL_POWER GND
J 0
(3600 750);
DISPLAY 0.893617 (3600 750);
PAINT GREEN (3600 750);
DISPLAY INVISIBLE (3600 750);
FORCEADD CAP_A..1
(2650 950);
FORCEPROP 1 LAST VALUE 47UF
J 0
(2700 1000);
DISPLAY 0.617021 (2700 1000);
PAINT SKYBLUE (2700 1000);
FORCEPROP 1 LAST PART_NUMBER 602433-106
J 0
(2700 800);
DISPLAY 0.617021 (2700 800);
PAINT BLUE (2700 800);
FORCEPROP 1 LAST PACK_TYPE 0603V
J 0
(2700 750);
DISPLAY 0.617021 (2700 750);
PAINT SKYBLUE (2700 750);
FORCEPROP 0 LAST GROUP PWR_MLCC_CAP
J 0
(2681 712);
DISPLAY 0.638298 (2681 712);
PAINT BROWN (2681 712);
DISPLAY BOTH (2681 712);
FORCEPROP 1 LASTPIN (2650 1050) $PN 1
J 0
(2660 1030);
DISPLAY 0.617021 (2660 1030);
PAINT ORANGE (2660 1030);
FORCEPROP 1 LAST TOLERANCE 20%
J 0
(2700 900);
DISPLAY 0.617021 (2700 900);
PAINT SKYBLUE (2700 900);
FORCEPROP 1 LAST VOLTAGE 4V
J 0
(2700 950);
DISPLAY 0.617021 (2700 950);
PAINT SKYBLUE (2700 950);
FORCEPROP 1 LASTPIN (2650 850) $PN 2
J 0
(2660 830);
DISPLAY 0.617021 (2660 830);
PAINT ORANGE (2660 830);
FORCEPROP 1 LAST MATERIAL X5R
J 0
(2700 850);
DISPLAY 0.617021 (2700 850);
PAINT SKYBLUE (2700 850);
FORCEPROP 1 LAST LOCATION C5L15
J 0
(2700 1050);
DISPLAY 0.617021 (2700 1050);
PAINT AQUA (2700 1050);
FORCEPROP 0 LAST BOM_SS NOPOP
J 0
(2675 650);
DISPLAY 0.638298 (2675 650);
PAINT BROWN (2675 650);
DISPLAY BOTH (2675 650);
FORCEPROP 2 LAST CDS_LOCATION C5L15
J 0
(2700 1050);
DISPLAY 0.617021 (2700 1050);
PAINT AQUA (2700 1050);
DISPLAY INVISIBLE (2700 1050);
FORCEPROP 2 LAST CDS_SEC 1
J 0
(2700 1100);
PAINT ORANGE (2700 1100);
DISPLAY INVISIBLE (2700 1100);
FORCEPROP 2 LAST SEC_TYPE 0603V
J 0
(2700 1150);
DISPLAY 1.021277 (2700 1150);
PAINT ORANGE (2700 1150);
DISPLAY INVISIBLE (2700 1150);
FORCEPROP 2 LAST SEC 1
J 0
(2700 1150);
DISPLAY 0.680851 (2700 1150);
PAINT MONO (2700 1150);
DISPLAY INVISIBLE (2700 1150);
FORCEPROP 1 LAST PATH I192
J 0
(2700 1100);
DISPLAY 0.978723 (2700 1100);
PAINT WHITE (2700 1100);
DISPLAY INVISIBLE (2700 1100);
FORCEPROP 2 LAST CDS_LIB dev_discrete
J 0
(2650 950);
PAINT ORANGE (2650 950);
DISPLAY INVISIBLE (2650 950);
FORCEADD CAP_A..1
(3000 950);
FORCEPROP 1 LAST VALUE 47UF
J 0
(3050 1000);
DISPLAY 0.617021 (3050 1000);
PAINT SKYBLUE (3050 1000);
FORCEPROP 1 LAST MATERIAL X5R
J 0
(3050 850);
DISPLAY 0.617021 (3050 850);
PAINT SKYBLUE (3050 850);
FORCEPROP 0 LAST GROUP PWR_MLCC_CAP
J 0
(3056 662);
DISPLAY 0.638298 (3056 662);
PAINT BROWN (3056 662);
DISPLAY BOTH (3056 662);
FORCEPROP 1 LAST PART_NUMBER 602433-106
J 0
(3050 800);
DISPLAY 0.617021 (3050 800);
PAINT BLUE (3050 800);
FORCEPROP 1 LAST PACK_TYPE 0603V
J 0
(3050 750);
DISPLAY 0.617021 (3050 750);
PAINT SKYBLUE (3050 750);
FORCEPROP 1 LASTPIN (3000 1050) $PN 1
J 0
(3010 1030);
DISPLAY 0.617021 (3010 1030);
PAINT ORANGE (3010 1030);
FORCEPROP 1 LASTPIN (3000 850) $PN 2
J 0
(3010 830);
DISPLAY 0.617021 (3010 830);
PAINT ORANGE (3010 830);
FORCEPROP 1 LAST TOLERANCE 20%
J 0
(3050 900);
DISPLAY 0.617021 (3050 900);
PAINT SKYBLUE (3050 900);
FORCEPROP 0 LAST BOM_SS NOPOP
J 0
(3050 625);
DISPLAY 0.638298 (3050 625);
PAINT BROWN (3050 625);
DISPLAY BOTH (3050 625);
FORCEPROP 1 LAST VOLTAGE 4V
J 0
(3050 950);
DISPLAY 0.617021 (3050 950);
PAINT SKYBLUE (3050 950);
FORCEPROP 1 LAST LOCATION C5A5
J 0
(3050 1050);
DISPLAY 0.617021 (3050 1050);
PAINT AQUA (3050 1050);
FORCEPROP 1 LAST PATH I193
J 0
(3050 1100);
DISPLAY 0.978723 (3050 1100);
PAINT WHITE (3050 1100);
DISPLAY INVISIBLE (3050 1100);
FORCEPROP 2 LAST CDS_LOCATION C5A5
J 0
(3050 1050);
DISPLAY 0.617021 (3050 1050);
PAINT AQUA (3050 1050);
DISPLAY INVISIBLE (3050 1050);
FORCEPROP 2 LAST CDS_SEC 1
J 0
(3050 1100);
PAINT ORANGE (3050 1100);
DISPLAY INVISIBLE (3050 1100);
FORCEPROP 2 LAST SEC_TYPE 0603V
J 0
(3050 1150);
DISPLAY 1.021277 (3050 1150);
PAINT ORANGE (3050 1150);
DISPLAY INVISIBLE (3050 1150);
FORCEPROP 2 LAST SEC 1
J 0
(3050 1150);
DISPLAY 0.680851 (3050 1150);
PAINT MONO (3050 1150);
DISPLAY INVISIBLE (3050 1150);
FORCEPROP 2 LAST CDS_LIB dev_discrete
J 0
(3000 950);
PAINT ORANGE (3000 950);
DISPLAY INVISIBLE (3000 950);
FORCEADD CAP_A..1
(3400 950);
FORCEPROP 1 LAST LOCATION C5B1
J 0
(3450 1050);
DISPLAY 0.617021 (3450 1050);
PAINT AQUA (3450 1050);
FORCEPROP 1 LAST VALUE 47UF
J 0
(3450 1000);
DISPLAY 0.617021 (3450 1000);
PAINT SKYBLUE (3450 1000);
FORCEPROP 1 LASTPIN (3400 1050) $PN 1
J 0
(3410 1030);
DISPLAY 0.617021 (3410 1030);
PAINT ORANGE (3410 1030);
FORCEPROP 1 LASTPIN (3400 850) $PN 2
J 0
(3410 830);
DISPLAY 0.617021 (3410 830);
PAINT ORANGE (3410 830);
FORCEPROP 1 LAST VOLTAGE 4V
J 0
(3450 950);
DISPLAY 0.617021 (3450 950);
PAINT SKYBLUE (3450 950);
FORCEPROP 0 LAST BOM_SS NOPOP
J 0
(3650 650);
DISPLAY 0.638298 (3650 650);
PAINT BROWN (3650 650);
DISPLAY BOTH (3650 650);
FORCEPROP 1 LAST TOLERANCE 20%
J 0
(3450 900);
DISPLAY 0.617021 (3450 900);
PAINT SKYBLUE (3450 900);
FORCEPROP 1 LAST MATERIAL X5R
J 0
(3450 850);
DISPLAY 0.617021 (3450 850);
PAINT SKYBLUE (3450 850);
FORCEPROP 1 LAST PART_NUMBER 602433-106
J 0
(3450 800);
DISPLAY 0.617021 (3450 800);
PAINT BLUE (3450 800);
FORCEPROP 1 LAST PACK_TYPE 0603V
J 0
(3450 750);
DISPLAY 0.617021 (3450 750);
PAINT SKYBLUE (3450 750);
FORCEPROP 0 LAST GROUP PWR_MLCC_CAP
J 0
(3456 712);
DISPLAY 0.638298 (3456 712);
PAINT BROWN (3456 712);
DISPLAY BOTH (3456 712);
FORCEPROP 2 LAST CDS_LOCATION C5B1
J 0
(3450 1050);
DISPLAY 0.617021 (3450 1050);
PAINT AQUA (3450 1050);
DISPLAY INVISIBLE (3450 1050);
FORCEPROP 2 LAST CDS_SEC 1
J 0
(3450 1100);
PAINT ORANGE (3450 1100);
DISPLAY INVISIBLE (3450 1100);
FORCEPROP 2 LAST SEC_TYPE 0603V
J 0
(3450 1150);
DISPLAY 1.021277 (3450 1150);
PAINT ORANGE (3450 1150);
DISPLAY INVISIBLE (3450 1150);
FORCEPROP 2 LAST SEC 1
J 0
(3450 1150);
DISPLAY 0.680851 (3450 1150);
PAINT MONO (3450 1150);
DISPLAY INVISIBLE (3450 1150);
FORCEPROP 1 LAST PATH I194
J 0
(3450 1100);
DISPLAY 0.978723 (3450 1100);
PAINT WHITE (3450 1100);
DISPLAY INVISIBLE (3450 1100);
FORCEPROP 2 LAST CDS_LIB dev_discrete
J 0
(3400 950);
PAINT ORANGE (3400 950);
DISPLAY INVISIBLE (3400 950);
FORCEADD CAP_A..1
(4125 1675);
FORCEPROP 1 LAST LOCATION C5M9
J 0
(4175 1775);
DISPLAY 0.617021 (4175 1775);
PAINT AQUA (4175 1775);
FORCEPROP 1 LASTPIN (4125 1775) $PN 1
J 0
(4135 1755);
DISPLAY 0.617021 (4135 1755);
PAINT ORANGE (4135 1755);
FORCEPROP 1 LAST MATERIAL X5R
J 0
(4175 1575);
DISPLAY 0.617021 (4175 1575);
PAINT SKYBLUE (4175 1575);
FORCEPROP 1 LAST PACK_TYPE 0603V
J 0
(4175 1475);
DISPLAY 0.617021 (4175 1475);
PAINT SKYBLUE (4175 1475);
FORCEPROP 1 LASTPIN (4125 1575) $PN 2
J 0
(4135 1555);
DISPLAY 0.617021 (4135 1555);
PAINT ORANGE (4135 1555);
FORCEPROP 1 LAST TOLERANCE 20%
J 0
(4175 1625);
DISPLAY 0.617021 (4175 1625);
PAINT SKYBLUE (4175 1625);
FORCEPROP 1 LAST VOLTAGE 4V
J 0
(4175 1675);
DISPLAY 0.617021 (4175 1675);
PAINT SKYBLUE (4175 1675);
FORCEPROP 1 LAST VALUE 47UF
J 0
(4175 1725);
DISPLAY 0.617021 (4175 1725);
PAINT SKYBLUE (4175 1725);
FORCEPROP 1 LAST PART_NUMBER 602433-106
J 0
(4175 1525);
DISPLAY 0.617021 (4175 1525);
PAINT BLUE (4175 1525);
FORCEPROP 0 LAST BOM_SS NOPOP
J 0
(4150 1350);
DISPLAY 0.638298 (4150 1350);
PAINT BROWN (4150 1350);
DISPLAY BOTH (4150 1350);
FORCEPROP 0 LAST GROUP PWR_MLCC_CAP
J 0
(4181 1437);
DISPLAY 0.638298 (4181 1437);
PAINT BROWN (4181 1437);
DISPLAY BOTH (4181 1437);
FORCEPROP 1 LAST PATH I195
J 0
(4175 1825);
DISPLAY 0.978723 (4175 1825);
PAINT WHITE (4175 1825);
DISPLAY INVISIBLE (4175 1825);
FORCEPROP 2 LAST SEC 1
J 0
(4175 1875);
DISPLAY 0.680851 (4175 1875);
PAINT MONO (4175 1875);
DISPLAY INVISIBLE (4175 1875);
FORCEPROP 2 LAST SEC_TYPE 0603V
J 0
(4175 1875);
DISPLAY 1.021277 (4175 1875);
PAINT ORANGE (4175 1875);
DISPLAY INVISIBLE (4175 1875);
FORCEPROP 2 LAST CDS_SEC 1
J 0
(4175 1825);
PAINT ORANGE (4175 1825);
DISPLAY INVISIBLE (4175 1825);
FORCEPROP 2 LAST CDS_LOCATION C5M9
J 0
(4175 1775);
DISPLAY 0.617021 (4175 1775);
PAINT AQUA (4175 1775);
DISPLAY INVISIBLE (4175 1775);
FORCEPROP 2 LAST CDS_LIB dev_discrete
J 0
(4125 1675);
PAINT ORANGE (4125 1675);
DISPLAY INVISIBLE (4125 1675);
FORCEADD CAP_A..1
(3775 1675);
FORCEPROP 0 LAST BOM_SS 078.1061T.M001
J 0
(3850 1300);
DISPLAY 0.638298 (3850 1300);
PAINT BROWN (3850 1300);
DISPLAY BOTH (3850 1300);
FORCEPROP 1 LASTPIN (3775 1775) $PN 1
J 0
(3785 1755);
DISPLAY 0.617021 (3785 1755);
PAINT ORANGE (3785 1755);
FORCEPROP 1 LAST TOLERANCE 20%
J 0
(3825 1625);
DISPLAY 0.617021 (3825 1625);
PAINT SKYBLUE (3825 1625);
FORCEPROP 1 LAST VOLTAGE 4V
J 0
(3825 1675);
DISPLAY 0.617021 (3825 1675);
PAINT SKYBLUE (3825 1675);
FORCEPROP 1 LAST MATERIAL X5R
J 0
(3825 1575);
DISPLAY 0.617021 (3825 1575);
PAINT SKYBLUE (3825 1575);
FORCEPROP 1 LASTPIN (3775 1575) $PN 2
J 0
(3785 1555);
DISPLAY 0.617021 (3785 1555);
PAINT ORANGE (3785 1555);
FORCEPROP 1 LAST LOCATION C4M5
J 0
(3825 1775);
DISPLAY 0.617021 (3825 1775);
PAINT AQUA (3825 1775);
FORCEPROP 1 LAST VALUE 47UF
J 0
(3825 1725);
DISPLAY 0.617021 (3825 1725);
PAINT SKYBLUE (3825 1725);
FORCEPROP 1 LAST PART_NUMBER 602433-106
J 0
(3825 1525);
DISPLAY 0.617021 (3825 1525);
PAINT BLUE (3825 1525);
FORCEPROP 1 LAST PACK_TYPE 0603V
J 0
(3825 1475);
DISPLAY 0.617021 (3825 1475);
PAINT SKYBLUE (3825 1475);
FORCEPROP 0 LAST GROUP PWR_MLCC_CAP
J 0
(3831 1387);
DISPLAY 0.638298 (3831 1387);
PAINT BROWN (3831 1387);
DISPLAY BOTH (3831 1387);
FORCEPROP 2 LAST SEC 1
J 0
(3825 1875);
DISPLAY 0.680851 (3825 1875);
PAINT MONO (3825 1875);
DISPLAY INVISIBLE (3825 1875);
FORCEPROP 1 LAST PATH I196
J 0
(3825 1825);
DISPLAY 0.978723 (3825 1825);
PAINT WHITE (3825 1825);
DISPLAY INVISIBLE (3825 1825);
FORCEPROP 2 LAST SEC_TYPE 0603V
J 0
(3825 1875);
DISPLAY 1.021277 (3825 1875);
PAINT ORANGE (3825 1875);
DISPLAY INVISIBLE (3825 1875);
FORCEPROP 2 LAST CDS_SEC 1
J 0
(3825 1825);
PAINT ORANGE (3825 1825);
DISPLAY INVISIBLE (3825 1825);
FORCEPROP 2 LAST CDS_LOCATION C4M5
J 0
(3825 1775);
DISPLAY 0.617021 (3825 1775);
PAINT AQUA (3825 1775);
DISPLAY INVISIBLE (3825 1775);
FORCEPROP 2 LAST CDS_LIB dev_discrete
J 0
(3775 1675);
PAINT ORANGE (3775 1675);
DISPLAY INVISIBLE (3775 1675);
FORCEADD CAP_A..1
(2675 1675);
FORCEPROP 0 LAST BOM_SS NOPOP
J 0
(2700 1375);
DISPLAY 0.638298 (2700 1375);
PAINT BROWN (2700 1375);
DISPLAY BOTH (2700 1375);
FORCEPROP 1 LASTPIN (2675 1775) $PN 1
J 0
(2685 1755);
DISPLAY 0.617021 (2685 1755);
PAINT ORANGE (2685 1755);
FORCEPROP 1 LASTPIN (2675 1575) $PN 2
J 0
(2685 1555);
DISPLAY 0.617021 (2685 1555);
PAINT ORANGE (2685 1555);
FORCEPROP 1 LAST VOLTAGE 4V
J 0
(2725 1675);
DISPLAY 0.617021 (2725 1675);
PAINT SKYBLUE (2725 1675);
FORCEPROP 1 LAST TOLERANCE 20%
J 0
(2725 1625);
DISPLAY 0.617021 (2725 1625);
PAINT SKYBLUE (2725 1625);
FORCEPROP 1 LAST PACK_TYPE 0603V
J 0
(2725 1475);
DISPLAY 0.617021 (2725 1475);
PAINT SKYBLUE (2725 1475);
FORCEPROP 1 LAST PART_NUMBER 602433-106
J 0
(2725 1525);
DISPLAY 0.617021 (2725 1525);
PAINT BLUE (2725 1525);
FORCEPROP 1 LAST MATERIAL X5R
J 0
(2725 1575);
DISPLAY 0.617021 (2725 1575);
PAINT SKYBLUE (2725 1575);
FORCEPROP 1 LAST LOCATION C5B2
J 0
(2725 1775);
DISPLAY 0.617021 (2725 1775);
PAINT AQUA (2725 1775);
FORCEPROP 1 LAST VALUE 47UF
J 0
(2725 1725);
DISPLAY 0.617021 (2725 1725);
PAINT SKYBLUE (2725 1725);
FORCEPROP 0 LAST GROUP PWR_MLCC_CAP
J 0
(2731 1437);
DISPLAY 0.638298 (2731 1437);
PAINT BROWN (2731 1437);
DISPLAY BOTH (2731 1437);
FORCEPROP 1 LAST PATH I197
J 0
(2725 1825);
DISPLAY 0.978723 (2725 1825);
PAINT WHITE (2725 1825);
DISPLAY INVISIBLE (2725 1825);
FORCEPROP 2 LAST SEC 1
J 0
(2725 1875);
DISPLAY 0.680851 (2725 1875);
PAINT MONO (2725 1875);
DISPLAY INVISIBLE (2725 1875);
FORCEPROP 2 LAST SEC_TYPE 0603V
J 0
(2725 1875);
DISPLAY 1.021277 (2725 1875);
PAINT ORANGE (2725 1875);
DISPLAY INVISIBLE (2725 1875);
FORCEPROP 2 LAST CDS_SEC 1
J 0
(2725 1825);
PAINT ORANGE (2725 1825);
DISPLAY INVISIBLE (2725 1825);
FORCEPROP 2 LAST CDS_LOCATION C5B2
J 0
(2725 1775);
DISPLAY 0.617021 (2725 1775);
PAINT AQUA (2725 1775);
DISPLAY INVISIBLE (2725 1775);
FORCEPROP 2 LAST CDS_LIB dev_discrete
J 0
(2675 1675);
PAINT ORANGE (2675 1675);
DISPLAY INVISIBLE (2675 1675);
FORCEADD CAP_A..1
(3025 1675);
FORCEPROP 1 LAST MATERIAL X5R
J 0
(3075 1575);
DISPLAY 0.617021 (3075 1575);
PAINT SKYBLUE (3075 1575);
FORCEPROP 1 LASTPIN (3025 1775) $PN 1
J 0
(3035 1755);
DISPLAY 0.617021 (3035 1755);
PAINT ORANGE (3035 1755);
FORCEPROP 1 LAST VOLTAGE 4V
J 0
(3075 1675);
DISPLAY 0.617021 (3075 1675);
PAINT SKYBLUE (3075 1675);
FORCEPROP 1 LASTPIN (3025 1575) $PN 2
J 0
(3035 1555);
DISPLAY 0.617021 (3035 1555);
PAINT ORANGE (3035 1555);
FORCEPROP 1 LAST TOLERANCE 20%
J 0
(3075 1625);
DISPLAY 0.617021 (3075 1625);
PAINT SKYBLUE (3075 1625);
FORCEPROP 1 LAST PART_NUMBER 602433-106
J 0
(3075 1525);
DISPLAY 0.617021 (3075 1525);
PAINT BLUE (3075 1525);
FORCEPROP 1 LAST PACK_TYPE 0603V
J 0
(3075 1475);
DISPLAY 0.617021 (3075 1475);
PAINT SKYBLUE (3075 1475);
FORCEPROP 0 LAST GROUP PWR_MLCC_CAP
J 0
(3081 1362);
DISPLAY 0.638298 (3081 1362);
PAINT BROWN (3081 1362);
DISPLAY BOTH (3081 1362);
FORCEPROP 0 LAST BOM_SS NOPOP
J 0
(3100 1325);
DISPLAY 0.638298 (3100 1325);
PAINT BROWN (3100 1325);
DISPLAY BOTH (3100 1325);
FORCEPROP 1 LAST VALUE 47UF
J 0
(3075 1725);
DISPLAY 0.617021 (3075 1725);
PAINT SKYBLUE (3075 1725);
FORCEPROP 1 LAST LOCATION C5M10
J 0
(3075 1775);
DISPLAY 0.617021 (3075 1775);
PAINT AQUA (3075 1775);
FORCEPROP 2 LAST CDS_LOCATION C5M10
J 0
(3075 1775);
DISPLAY 0.617021 (3075 1775);
PAINT AQUA (3075 1775);
DISPLAY INVISIBLE (3075 1775);
FORCEPROP 2 LAST CDS_SEC 1
J 0
(3075 1825);
PAINT ORANGE (3075 1825);
DISPLAY INVISIBLE (3075 1825);
FORCEPROP 2 LAST SEC_TYPE 0603V
J 0
(3075 1875);
DISPLAY 1.021277 (3075 1875);
PAINT ORANGE (3075 1875);
DISPLAY INVISIBLE (3075 1875);
FORCEPROP 2 LAST SEC 1
J 0
(3075 1875);
DISPLAY 0.680851 (3075 1875);
PAINT MONO (3075 1875);
DISPLAY INVISIBLE (3075 1875);
FORCEPROP 1 LAST PATH I198
J 0
(3075 1825);
DISPLAY 0.978723 (3075 1825);
PAINT WHITE (3075 1825);
DISPLAY INVISIBLE (3075 1825);
FORCEPROP 2 LAST CDS_LIB dev_discrete
J 0
(3025 1675);
PAINT ORANGE (3025 1675);
DISPLAY INVISIBLE (3025 1675);
FORCEADD CAP_A..1
(3425 1675);
FORCEPROP 1 LAST VALUE 47UF
J 0
(3475 1725);
DISPLAY 0.617021 (3475 1725);
PAINT SKYBLUE (3475 1725);
FORCEPROP 1 LASTPIN (3425 1575) $PN 2
J 0
(3435 1555);
DISPLAY 0.617021 (3435 1555);
PAINT ORANGE (3435 1555);
FORCEPROP 1 LASTPIN (3425 1775) $PN 1
J 0
(3435 1755);
DISPLAY 0.617021 (3435 1755);
PAINT ORANGE (3435 1755);
FORCEPROP 1 LAST LOCATION C5M3
J 0
(3475 1775);
DISPLAY 0.617021 (3475 1775);
PAINT AQUA (3475 1775);
FORCEPROP 1 LAST VOLTAGE 4V
J 0
(3475 1675);
DISPLAY 0.617021 (3475 1675);
PAINT SKYBLUE (3475 1675);
FORCEPROP 1 LAST TOLERANCE 20%
J 0
(3475 1625);
DISPLAY 0.617021 (3475 1625);
PAINT SKYBLUE (3475 1625);
FORCEPROP 1 LAST PACK_TYPE 0603V
J 0
(3475 1475);
DISPLAY 0.617021 (3475 1475);
PAINT SKYBLUE (3475 1475);
FORCEPROP 1 LAST PART_NUMBER 602433-106
J 0
(3475 1525);
DISPLAY 0.617021 (3475 1525);
PAINT BLUE (3475 1525);
FORCEPROP 1 LAST MATERIAL X5R
J 0
(3475 1575);
DISPLAY 0.617021 (3475 1575);
PAINT SKYBLUE (3475 1575);
FORCEPROP 0 LAST GROUP PWR_MLCC_CAP
J 0
(3481 1437);
DISPLAY 0.638298 (3481 1437);
PAINT BROWN (3481 1437);
DISPLAY BOTH (3481 1437);
FORCEPROP 0 LAST BOM_SS NOPOP
J 0
(3500 1325);
DISPLAY 0.638298 (3500 1325);
PAINT BROWN (3500 1325);
DISPLAY BOTH (3500 1325);
FORCEPROP 2 LAST CDS_SEC 1
J 0
(3475 1825);
PAINT ORANGE (3475 1825);
DISPLAY INVISIBLE (3475 1825);
FORCEPROP 2 LAST SEC_TYPE 0603V
J 0
(3475 1875);
DISPLAY 1.021277 (3475 1875);
PAINT ORANGE (3475 1875);
DISPLAY INVISIBLE (3475 1875);
FORCEPROP 2 LAST SEC 1
J 0
(3475 1875);
DISPLAY 0.680851 (3475 1875);
PAINT MONO (3475 1875);
DISPLAY INVISIBLE (3475 1875);
FORCEPROP 1 LAST PATH I199
J 0
(3475 1825);
DISPLAY 0.978723 (3475 1825);
PAINT WHITE (3475 1825);
DISPLAY INVISIBLE (3475 1825);
FORCEPROP 2 LAST CDS_LOCATION C5M3
J 0
(3475 1775);
DISPLAY 0.617021 (3475 1775);
PAINT AQUA (3475 1775);
DISPLAY INVISIBLE (3475 1775);
FORCEPROP 2 LAST CDS_LIB dev_discrete
J 0
(3425 1675);
PAINT ORANGE (3425 1675);
DISPLAY INVISIBLE (3425 1675);
FORCEADD CAP_A..1
(4525 1675);
FORCEPROP 1 LAST PACK_TYPE 0603V
J 0
(4575 1475);
DISPLAY 0.617021 (4575 1475);
PAINT SKYBLUE (4575 1475);
FORCEPROP 1 LAST LOCATION C5M11
J 0
(4575 1775);
DISPLAY 0.617021 (4575 1775);
PAINT AQUA (4575 1775);
FORCEPROP 1 LAST VALUE 47UF
J 0
(4575 1725);
DISPLAY 0.617021 (4575 1725);
PAINT SKYBLUE (4575 1725);
FORCEPROP 1 LAST TOLERANCE 20%
J 0
(4575 1625);
DISPLAY 0.617021 (4575 1625);
PAINT SKYBLUE (4575 1625);
FORCEPROP 1 LAST MATERIAL X5R
J 0
(4575 1575);
DISPLAY 0.617021 (4575 1575);
PAINT SKYBLUE (4575 1575);
FORCEPROP 1 LASTPIN (4525 1775) $PN 1
J 0
(4535 1755);
DISPLAY 0.617021 (4535 1755);
PAINT ORANGE (4535 1755);
FORCEPROP 1 LASTPIN (4525 1575) $PN 2
J 0
(4535 1555);
DISPLAY 0.617021 (4535 1555);
PAINT ORANGE (4535 1555);
FORCEPROP 1 LAST PART_NUMBER 602433-106
J 0
(4575 1525);
DISPLAY 0.617021 (4575 1525);
PAINT BLUE (4575 1525);
FORCEPROP 1 LAST VOLTAGE 4V
J 0
(4575 1675);
DISPLAY 0.617021 (4575 1675);
PAINT SKYBLUE (4575 1675);
FORCEPROP 0 LAST BOM_SS NOPOP
J 0
(4600 1325);
DISPLAY 0.638298 (4600 1325);
PAINT BROWN (4600 1325);
DISPLAY BOTH (4600 1325);
FORCEPROP 0 LAST GROUP PWR_MLCC_CAP
J 0
(4581 1387);
DISPLAY 0.638298 (4581 1387);
PAINT BROWN (4581 1387);
DISPLAY BOTH (4581 1387);
FORCEPROP 2 LAST SEC 1
J 0
(4575 1875);
DISPLAY 0.680851 (4575 1875);
PAINT MONO (4575 1875);
DISPLAY INVISIBLE (4575 1875);
FORCEPROP 1 LAST PATH I200
J 0
(4575 1825);
DISPLAY 0.978723 (4575 1825);
PAINT WHITE (4575 1825);
DISPLAY INVISIBLE (4575 1825);
FORCEPROP 2 LAST CDS_SEC 1
J 0
(4575 1825);
PAINT ORANGE (4575 1825);
DISPLAY INVISIBLE (4575 1825);
FORCEPROP 2 LAST SEC_TYPE 0603V
J 0
(4575 1875);
DISPLAY 1.021277 (4575 1875);
PAINT ORANGE (4575 1875);
DISPLAY INVISIBLE (4575 1875);
FORCEPROP 2 LAST CDS_LOCATION C5M11
J 0
(4575 1775);
DISPLAY 0.617021 (4575 1775);
PAINT AQUA (4575 1775);
DISPLAY INVISIBLE (4575 1775);
FORCEPROP 2 LAST CDS_LIB dev_discrete
J 0
(4525 1675);
PAINT ORANGE (4525 1675);
DISPLAY INVISIBLE (4525 1675);
FORCEADD PVDDQ_DEF..1
(-1450 3250);
FORCEPROP 3 LASTPIN (-1450 3200) SIG_NAME PVDDQ_DEF\g
J 0
(-1440 3210);
DISPLAY 0.659574 (-1440 3210);
PAINT MONO (-1440 3210);
DISPLAY INVISIBLE (-1440 3210);
FORCEPROP 1 LAST HDL_POWER PVDDQ_DEF
J 1
(-1450 3300);
DISPLAY 0.872340 (-1450 3300);
PAINT GREEN (-1450 3300);
DISPLAY INVISIBLE (-1450 3300);
FORCEPROP 1 LAST BODY_TYPE PLUMBING
J 0
(-1495 3207);
DISPLAY 0.340426 (-1495 3207);
PAINT GREEN (-1495 3207);
DISPLAY INVISIBLE (-1495 3207);
FORCEPROP 1 LAST VOLTAGE 1.2V
J 0
(-1495 3207);
DISPLAY 0.340426 (-1495 3207);
PAINT SKYBLUE (-1495 3207);
DISPLAY INVISIBLE (-1495 3207);
FORCEPROP 1 LAST PATH I201
J 0
(-1400 3275);
DISPLAY 0.872340 (-1400 3275);
PAINT AQUA (-1400 3275);
DISPLAY INVISIBLE (-1400 3275);
FORCEPROP 2 LAST CDS_LIB mstr_symbols
J 0
(-1450 3250);
PAINT ORANGE (-1450 3250);
DISPLAY INVISIBLE (-1450 3250);
FORCEPROP 2 LAST BOM_COST MEM_VRD_PVPP_DEF
J 0
(-1400 3350);
PAINT MONO (-1400 3350);
DISPLAY INVISIBLE (-1400 3350);
FORCEPROP 2 LAST ROOM VDDQ_DEF_PWR_VR
J 0
(-1225 3350);
PAINT ORANGE (-1225 3350);
DISPLAY INVISIBLE (-1225 3350);
FORCEADD GND..1
(-1950 2475);
FORCEPROP 3 LASTPIN (-1950 2525) SIG_NAME GND\g
J 0
(-1940 2535);
DISPLAY 0.659574 (-1940 2535);
PAINT MONO (-1940 2535);
DISPLAY INVISIBLE (-1940 2535);
FORCEPROP 1 LAST VOLTAGE 0
J 0
(-1950 2475);
PAINT SKYBLUE (-1950 2475);
DISPLAY INVISIBLE (-1950 2475);
FORCEPROP 2 LAST CDS_LIB mstr_symbols
J 0
(-1950 2475);
PAINT ORANGE (-1950 2475);
DISPLAY INVISIBLE (-1950 2475);
FORCEPROP 1 LAST PATH I202
J 0
(-1875 2475);
DISPLAY 0.872340 (-1875 2475);
PAINT AQUA (-1875 2475);
DISPLAY INVISIBLE (-1875 2475);
FORCEPROP 1 LAST SIZE 1B
J 0
(-1875 2425);
DISPLAY 0.893617 (-1875 2425);
PAINT GREEN (-1875 2425);
DISPLAY INVISIBLE (-1875 2425);
FORCEPROP 2 LAST BOM_COST MEM_VRD_PVDDQ_CD
J 0
(-2275 2550);
PAINT MONO (-2275 2550);
DISPLAY INVISIBLE (-2275 2550);
FORCEPROP 2 LAST ROOM VDDQ_ABC_PWR_VR
J 0
(-2500 2550);
PAINT ORANGE (-2500 2550);
DISPLAY INVISIBLE (-2500 2550);
FORCEPROP 1 LAST BODY_TYPE PLUMBING
J 0
(-1995 2432);
DISPLAY 0.340426 (-1995 2432);
PAINT GREEN (-1995 2432);
DISPLAY INVISIBLE (-1995 2432);
FORCEPROP 1 LAST HDL_POWER GND
J 0
(-1950 2625);
DISPLAY 0.893617 (-1950 2625);
PAINT GREEN (-1950 2625);
DISPLAY INVISIBLE (-1950 2625);
FORCEADD PVDDQ_DEF..1
(-2150 350);
FORCEPROP 3 LASTPIN (-2150 300) SIG_NAME PVDDQ_DEF\g
J 0
(-2140 310);
DISPLAY 0.659574 (-2140 310);
PAINT MONO (-2140 310);
DISPLAY INVISIBLE (-2140 310);
FORCEPROP 1 LAST VOLTAGE 1.2V
J 0
(-2195 307);
DISPLAY 0.340426 (-2195 307);
PAINT SKYBLUE (-2195 307);
DISPLAY INVISIBLE (-2195 307);
FORCEPROP 2 LAST CDS_LIB mstr_symbols
J 0
(-2150 350);
PAINT ORANGE (-2150 350);
DISPLAY INVISIBLE (-2150 350);
FORCEPROP 1 LAST PATH I218
J 0
(-2100 375);
DISPLAY 0.872340 (-2100 375);
PAINT AQUA (-2100 375);
DISPLAY INVISIBLE (-2100 375);
FORCEPROP 1 LAST BODY_TYPE PLUMBING
J 0
(-2195 307);
DISPLAY 0.340426 (-2195 307);
PAINT GREEN (-2195 307);
DISPLAY INVISIBLE (-2195 307);
FORCEPROP 1 LAST HDL_POWER PVDDQ_DEF
J 1
(-2150 400);
DISPLAY 0.872340 (-2150 400);
PAINT GREEN (-2150 400);
DISPLAY INVISIBLE (-2150 400);
FORCEADD GND..1
(-2150 -225);
FORCEPROP 3 LASTPIN (-2150 -175) SIG_NAME GND\g
J 0
(-2140 -165);
DISPLAY 0.659574 (-2140 -165);
PAINT MONO (-2140 -165);
DISPLAY INVISIBLE (-2140 -165);
FORCEPROP 2 LAST ROOM VDDQ_ABC_PWR_VR
J 0
(-2700 -150);
DISPLAY 1.936170 (-2700 -150);
PAINT ORANGE (-2700 -150);
DISPLAY INVISIBLE (-2700 -150);
FORCEPROP 2 LAST BOM_COST PROC_VRD_VCCIN_CPU0
J 0
(-2525 -150);
DISPLAY 1.446809 (-2525 -150);
PAINT MONO (-2525 -150);
DISPLAY INVISIBLE (-2525 -150);
FORCEPROP 1 LAST PATH I220
J 0
(-2075 -225);
DISPLAY 0.872340 (-2075 -225);
PAINT AQUA (-2075 -225);
DISPLAY INVISIBLE (-2075 -225);
FORCEPROP 2 LAST CDS_LIB mstr_symbols
J 0
(-2150 -225);
PAINT ORANGE (-2150 -225);
DISPLAY INVISIBLE (-2150 -225);
FORCEPROP 1 LAST SIZE 1B
J 0
(-2075 -275);
DISPLAY 1.723404 (-2075 -275);
PAINT GREEN (-2075 -275);
DISPLAY INVISIBLE (-2075 -275);
FORCEPROP 1 LAST VOLTAGE 0
J 0
(-2150 -225);
PAINT SKYBLUE (-2150 -225);
DISPLAY INVISIBLE (-2150 -225);
FORCEPROP 1 LAST BODY_TYPE PLUMBING
J 0
(-2195 -268);
DISPLAY 0.340426 (-2195 -268);
PAINT GREEN (-2195 -268);
DISPLAY INVISIBLE (-2195 -268);
FORCEPROP 1 LAST HDL_POWER GND
J 0
(-2150 -75);
DISPLAY 1.723404 (-2150 -75);
PAINT GREEN (-2150 -75);
DISPLAY INVISIBLE (-2150 -75);
FORCEADD PVDDQ_DEF..1
(-2150 -400);
FORCEPROP 3 LASTPIN (-2150 -450) SIG_NAME PVDDQ_DEF\g
J 0
(-2140 -440);
DISPLAY 0.659574 (-2140 -440);
PAINT MONO (-2140 -440);
DISPLAY INVISIBLE (-2140 -440);
FORCEPROP 2 LAST ROOM VDDQ_DEF_PWR_VR
J 0
(-2150 -300);
DISPLAY 1.936170 (-2150 -300);
PAINT ORANGE (-2150 -300);
DISPLAY INVISIBLE (-2150 -300);
FORCEPROP 2 LAST BOM_COST PROC_SOCKET 
J 0
(-2150 -300);
DISPLAY 1.446809 (-2150 -300);
PAINT MONO (-2150 -300);
DISPLAY INVISIBLE (-2150 -300);
FORCEPROP 1 LAST PATH I235
J 0
(-2100 -375);
DISPLAY 0.872340 (-2100 -375);
PAINT AQUA (-2100 -375);
DISPLAY INVISIBLE (-2100 -375);
FORCEPROP 2 LAST CDS_LIB mstr_symbols
J 0
(-2150 -400);
PAINT ORANGE (-2150 -400);
DISPLAY INVISIBLE (-2150 -400);
FORCEPROP 1 LAST VOLTAGE 1.2V
J 0
(-2195 -443);
DISPLAY 0.340426 (-2195 -443);
PAINT SKYBLUE (-2195 -443);
DISPLAY INVISIBLE (-2195 -443);
FORCEPROP 1 LAST BODY_TYPE PLUMBING
J 0
(-2195 -443);
DISPLAY 0.340426 (-2195 -443);
PAINT GREEN (-2195 -443);
DISPLAY INVISIBLE (-2195 -443);
FORCEPROP 1 LAST HDL_POWER PVDDQ_DEF
J 1
(-2150 -350);
DISPLAY 0.872340 (-2150 -350);
PAINT GREEN (-2150 -350);
DISPLAY INVISIBLE (-2150 -350);
FORCEADD GND..1
(-2150 -1000);
FORCEPROP 3 LASTPIN (-2150 -950) SIG_NAME GND\g
J 0
(-2140 -940);
DISPLAY 0.659574 (-2140 -940);
PAINT MONO (-2140 -940);
DISPLAY INVISIBLE (-2140 -940);
FORCEPROP 2 LAST ROOM VDDQ_ABC_PWR_VR
J 0
(-2700 -925);
DISPLAY 1.936170 (-2700 -925);
PAINT ORANGE (-2700 -925);
DISPLAY INVISIBLE (-2700 -925);
FORCEPROP 2 LAST BOM_COST PROC_VRD_VCCIN_CPU0
J 0
(-2525 -925);
DISPLAY 1.446809 (-2525 -925);
PAINT MONO (-2525 -925);
DISPLAY INVISIBLE (-2525 -925);
FORCEPROP 1 LAST SIZE 1B
J 0
(-2075 -1050);
DISPLAY 1.723404 (-2075 -1050);
PAINT GREEN (-2075 -1050);
DISPLAY INVISIBLE (-2075 -1050);
FORCEPROP 1 LAST PATH I238
J 0
(-2075 -1000);
DISPLAY 0.872340 (-2075 -1000);
PAINT AQUA (-2075 -1000);
DISPLAY INVISIBLE (-2075 -1000);
FORCEPROP 2 LAST CDS_LIB mstr_symbols
J 0
(-2150 -1000);
PAINT ORANGE (-2150 -1000);
DISPLAY INVISIBLE (-2150 -1000);
FORCEPROP 1 LAST VOLTAGE 0
J 0
(-2150 -1000);
PAINT SKYBLUE (-2150 -1000);
DISPLAY INVISIBLE (-2150 -1000);
FORCEPROP 1 LAST BODY_TYPE PLUMBING
J 0
(-2195 -1043);
DISPLAY 0.340426 (-2195 -1043);
PAINT GREEN (-2195 -1043);
DISPLAY INVISIBLE (-2195 -1043);
FORCEPROP 1 LAST HDL_POWER GND
J 0
(-2150 -850);
DISPLAY 1.723404 (-2150 -850);
PAINT GREEN (-2150 -850);
DISPLAY INVISIBLE (-2150 -850);
FORCEADD SHUNT..1
(-300 2075);
FORCEPROP 1 LAST LOCATION SH4L2
J 0
(-375 2125);
DISPLAY 0.617021 (-375 2125);
PAINT AQUA (-375 2125);
FORCEPROP 1 LASTPIN (-150 2075) $PN 2
J 0
(-190 2085);
DISPLAY 0.617021 (-190 2085);
PAINT ORANGE (-190 2085);
FORCEPROP 1 LASTPIN (-450 2075) $PN 1
J 2
(-400 2085);
DISPLAY 0.617021 (-400 2085);
PAINT ORANGE (-400 2085);
FORCEPROP 1 LAST PART_NUMBER N_A
J 0
(-375 1985);
DISPLAY 0.617021 (-375 1985);
PAINT BLUE (-375 1985);
FORCEPROP 2 LAST SEC_TYPE SH0201
J 0
(-350 2225);
DISPLAY 1.021277 (-350 2225);
PAINT ORANGE (-350 2225);
DISPLAY INVISIBLE (-350 2225);
FORCEPROP 1 LAST PATH I239
J 0
(-350 2175);
DISPLAY 0.978723 (-350 2175);
PAINT ORANGE (-350 2175);
DISPLAY INVISIBLE (-350 2175);
FORCEPROP 0 LAST SEC 1
J 0
(-375 2175);
DISPLAY 0.680851 (-375 2175);
PAINT MONO (-375 2175);
DISPLAY INVISIBLE (-375 2175);
FORCEPROP 2 LAST CDS_LIB mstr_misc
J 0
(-300 2075);
PAINT ORANGE (-300 2075);
DISPLAY INVISIBLE (-300 2075);
FORCEPROP 1 LAST MATERIAL EMPTY
J 0
(-375 1940);
DISPLAY 0.978723 (-375 1940);
PAINT RED (-375 1940);
DISPLAY INVISIBLE (-375 1940);
FORCEPROP 1 LAST PACK_TYPE SH0201
J 0
(-360 1890);
DISPLAY 0.978723 (-360 1890);
PAINT SKYBLUE (-360 1890);
DISPLAY INVISIBLE (-360 1890);
FORCEPROP 1 LAST PIN_SHORT A:B
J 0
(-375 1825);
DISPLAY 1.021277 (-375 1825);
PAINT ORANGE (-375 1825);
DISPLAY INVISIBLE (-375 1825);
FORCEADD SHUNT..1
(-325 1625);
FORCEPROP 1 LAST LOCATION SH4L1
J 0
(-400 1675);
DISPLAY 0.617021 (-400 1675);
PAINT AQUA (-400 1675);
FORCEPROP 1 LASTPIN (-475 1625) $PN 1
J 2
(-425 1635);
DISPLAY 0.617021 (-425 1635);
PAINT ORANGE (-425 1635);
FORCEPROP 1 LAST PART_NUMBER N_A
J 0
(-400 1535);
DISPLAY 0.617021 (-400 1535);
PAINT BLUE (-400 1535);
FORCEPROP 1 LASTPIN (-175 1625) $PN 2
J 0
(-215 1635);
DISPLAY 0.617021 (-215 1635);
PAINT ORANGE (-215 1635);
FORCEPROP 2 LAST SEC_TYPE SH0201
J 0
(-375 1775);
DISPLAY 1.021277 (-375 1775);
PAINT ORANGE (-375 1775);
DISPLAY INVISIBLE (-375 1775);
FORCEPROP 1 LAST PATH I240
J 0
(-375 1725);
DISPLAY 0.978723 (-375 1725);
PAINT ORANGE (-375 1725);
DISPLAY INVISIBLE (-375 1725);
FORCEPROP 2 LAST CDS_LIB mstr_misc
J 0
(-325 1625);
PAINT ORANGE (-325 1625);
DISPLAY INVISIBLE (-325 1625);
FORCEPROP 0 LAST SEC 1
J 0
(-400 1725);
DISPLAY 0.680851 (-400 1725);
PAINT MONO (-400 1725);
DISPLAY INVISIBLE (-400 1725);
FORCEPROP 1 LAST MATERIAL EMPTY
J 0
(-400 1490);
DISPLAY 0.978723 (-400 1490);
PAINT RED (-400 1490);
DISPLAY INVISIBLE (-400 1490);
FORCEPROP 1 LAST PACK_TYPE SH0201
J 0
(-385 1440);
DISPLAY 0.978723 (-385 1440);
PAINT SKYBLUE (-385 1440);
DISPLAY INVISIBLE (-385 1440);
FORCEPROP 1 LAST PIN_SHORT A:B
J 0
(-400 1375);
DISPLAY 1.021277 (-400 1375);
PAINT ORANGE (-400 1375);
DISPLAY INVISIBLE (-400 1375);
FORCEADD IND-100NH-35-GP..1
R 1
(-1950 1325);
FORCEPROP 2 LAST RATED ISAT=16A@25C
J 0
(-2100 1150);
DISPLAY 0.638298 (-2100 1150);
PAINT GREEN (-2100 1150);
FORCEPROP 2 LAST TYPE IRMS=29A@DELTA_T<45C
J 0
(-2100 1100);
DISPLAY 0.638298 (-2100 1100);
PAINT GREEN (-2100 1100);
FORCEPROP 2 LAST PACK_SIZE DCR=0.16MOHM
J 0
(-2100 1050);
DISPLAY 0.638298 (-2100 1050);
PAINT GREEN (-2100 1050);
FORCEPROP 2 LAST ATTRIBUTE 100NH
J 0
(-2100 1200);
DISPLAY 0.638298 (-2100 1200);
PAINT GREEN (-2100 1200);
FORCEPROP 1 LAST VALUE IND-100NH-35-GP
J 0
(-2100 1250);
DISPLAY 0.617021 (-2100 1250);
PAINT GREEN (-2100 1250);
FORCEPROP 2 LASTPIN (-1800 1300) $PN 2
J 0
(-1790 1310);
DISPLAY 0.808511 (-1790 1310);
PAINT ORANGE (-1790 1310);
FORCEPROP 2 LASTPIN (-2100 1300) $PN 1
J 2
(-2110 1310);
DISPLAY 0.808511 (-2110 1310);
PAINT ORANGE (-2110 1310);
FORCEPROP 1 LAST LOCATION L7A5
J 0
(-2075 1375);
DISPLAY 0.617021 (-2075 1375);
PAINT GREEN (-2075 1375);
FORCEPROP 1 LAST CDS_LMAN_SYM_OUTLINE -75,100,75,-100
R 1
J 0
(-1950 1325);
DISPLAY 0.468085 (-1950 1325);
PAINT GREEN (-1950 1325);
DISPLAY INVISIBLE (-1950 1325);
FORCEPROP 2 LAST CDS_LIB w_hdl
R 1
J 0
(-1950 1325);
PAINT MONO (-1950 1325);
DISPLAY INVISIBLE (-1950 1325);
FORCEPROP 1 LAST PART_NUMBER 068.1011N.M001
R 1
J 0
(-1950 1325);
DISPLAY 0.617021 (-1950 1325);
PAINT GREEN (-1950 1325);
DISPLAY INVISIBLE (-1950 1325);
FORCEPROP 2 LAST SEC_TYPE DISCRET-G8
J 0
(-2100 1300);
DISPLAY 1.021277 (-2100 1300);
PAINT ORANGE (-2100 1300);
DISPLAY INVISIBLE (-2100 1300);
FORCEPROP 2 LAST SEC 1
J 0
(-2100 1300);
DISPLAY 0.680851 (-2100 1300);
PAINT MONO (-2100 1300);
DISPLAY INVISIBLE (-2100 1300);
FORCEPROP 1 LAST PACK_TYPE DISCRET-G8
R 1
J 0
(-1950 1325);
DISPLAY 0.617021 (-1950 1325);
PAINT GREEN (-1950 1325);
DISPLAY INVISIBLE (-1950 1325);
FORCEPROP 1 LAST PATH I241
R 1
J 0
(-1950 1325);
DISPLAY 0.617021 (-1950 1325);
PAINT GREEN (-1950 1325);
DISPLAY INVISIBLE (-1950 1325);
FORCEADD GND..1
(175 2525);
FORCEPROP 3 LASTPIN (175 2575) SIG_NAME GND\g
J 0
(185 2585);
DISPLAY 0.659574 (185 2585);
PAINT MONO (185 2585);
DISPLAY INVISIBLE (185 2585);
FORCEPROP 1 LAST HDL_POWER GND
J 0
(175 2675);
DISPLAY 0.893617 (175 2675);
PAINT GREEN (175 2675);
DISPLAY INVISIBLE (175 2675);
FORCEPROP 1 LAST BODY_TYPE PLUMBING
J 0
(130 2482);
DISPLAY 0.340426 (130 2482);
PAINT GREEN (130 2482);
DISPLAY INVISIBLE (130 2482);
FORCEPROP 1 LAST VOLTAGE 0
J 0
(175 2525);
PAINT SKYBLUE (175 2525);
DISPLAY INVISIBLE (175 2525);
FORCEPROP 1 LAST SIZE 1B
J 0
(250 2475);
DISPLAY 0.893617 (250 2475);
PAINT GREEN (250 2475);
DISPLAY INVISIBLE (250 2475);
FORCEPROP 2 LAST CDS_LIB mstr_symbols
J 0
(175 2525);
PAINT ORANGE (175 2525);
DISPLAY INVISIBLE (175 2525);
FORCEPROP 1 LAST PATH I245
J 0
(250 2525);
DISPLAY 0.872340 (250 2525);
PAINT AQUA (250 2525);
DISPLAY INVISIBLE (250 2525);
FORCEADD PVDDQ_DEF..1
(175 3200);
FORCEPROP 3 LASTPIN (175 3150) SIG_NAME PVDDQ_DEF\g
J 0
(185 3160);
DISPLAY 0.659574 (185 3160);
PAINT MONO (185 3160);
DISPLAY INVISIBLE (185 3160);
FORCEPROP 1 LAST PATH I248
J 0
(225 3225);
DISPLAY 0.872340 (225 3225);
PAINT AQUA (225 3225);
DISPLAY INVISIBLE (225 3225);
FORCEPROP 1 LAST HDL_POWER PVDDQ_DEF
J 1
(175 3250);
DISPLAY 0.872340 (175 3250);
PAINT GREEN (175 3250);
DISPLAY INVISIBLE (175 3250);
FORCEPROP 1 LAST BODY_TYPE PLUMBING
J 0
(130 3157);
DISPLAY 0.340426 (130 3157);
PAINT GREEN (130 3157);
DISPLAY INVISIBLE (130 3157);
FORCEPROP 1 LAST VOLTAGE 1.2V
J 0
(130 3157);
DISPLAY 0.340426 (130 3157);
PAINT SKYBLUE (130 3157);
DISPLAY INVISIBLE (130 3157);
FORCEPROP 2 LAST BOM_COST MEM_VRD_PVPP_DEF
J 0
(225 3300);
PAINT MONO (225 3300);
DISPLAY INVISIBLE (225 3300);
FORCEPROP 2 LAST ROOM VDDQ_DEF_PWR_VR
J 0
(400 3300);
PAINT ORANGE (400 3300);
DISPLAY INVISIBLE (400 3300);
FORCEPROP 2 LAST CDS_LIB mstr_symbols
J 0
(175 3200);
PAINT ORANGE (175 3200);
DISPLAY INVISIBLE (175 3200);
FORCEADD CAP_A..1
(1550 2050);
FORCEPROP 1 LAST LOCATION C5D4
J 0
(1600 2150);
DISPLAY 0.617021 (1600 2150);
PAINT AQUA (1600 2150);
FORCEPROP 0 LAST GROUP PWR_MLCC_CAP
J 0
(1606 1762);
DISPLAY 0.638298 (1606 1762);
PAINT BROWN (1606 1762);
DISPLAY BOTH (1606 1762);
FORCEPROP 1 LAST PART_NUMBER E15431-004
J 0
(1600 1900);
DISPLAY 0.617021 (1600 1900);
PAINT BLUE (1600 1900);
FORCEPROP 1 LAST PACK_TYPE 0603V
J 0
(1600 1850);
DISPLAY 0.617021 (1600 1850);
PAINT SKYBLUE (1600 1850);
FORCEPROP 1 LAST MATERIAL X6S
J 0
(1600 1950);
DISPLAY 0.617021 (1600 1950);
PAINT SKYBLUE (1600 1950);
FORCEPROP 1 LAST TOLERANCE 20%
J 0
(1600 2000);
DISPLAY 0.617021 (1600 2000);
PAINT SKYBLUE (1600 2000);
FORCEPROP 1 LAST VOLTAGE 4V
J 0
(1600 2050);
DISPLAY 0.617021 (1600 2050);
PAINT SKYBLUE (1600 2050);
FORCEPROP 1 LASTPIN (1550 2150) $PN 1
J 0
(1560 2130);
DISPLAY 0.617021 (1560 2130);
PAINT GREEN (1560 2130);
FORCEPROP 1 LASTPIN (1550 1950) $PN 2
J 0
(1560 1930);
DISPLAY 0.617021 (1560 1930);
PAINT GREEN (1560 1930);
FORCEPROP 1 LAST VALUE 22.0UF
J 0
(1600 2100);
DISPLAY 0.617021 (1600 2100);
PAINT SKYBLUE (1600 2100);
FORCEPROP 1 LAST PATH I249
J 0
(1600 2200);
DISPLAY 0.978723 (1600 2200);
PAINT WHITE (1600 2200);
DISPLAY INVISIBLE (1600 2200);
FORCEPROP 2 LAST ROOM PVCCIN_CPU0_DECAP_VR
J 0
(1600 2200);
DISPLAY 1.021277 (1600 2200);
PAINT ORANGE (1600 2200);
DISPLAY INVISIBLE (1600 2200);
FORCEPROP 2 LAST $SEC 1
J 0
(1600 2250);
PAINT MONO (1600 2250);
DISPLAY INVISIBLE (1600 2250);
FORCEPROP 2 LAST CDS_SEC 1
J 0
(1600 2250);
PAINT MONO (1600 2250);
DISPLAY INVISIBLE (1600 2250);
FORCEPROP 2 LAST CDS_LIB dev_discrete
J 0
(1550 2050);
PAINT ORANGE (1550 2050);
DISPLAY INVISIBLE (1550 2050);
FORCEPROP 2 LAST BOM_COST PROC_SOCKET
J 0
(1600 2250);
DISPLAY 1.021277 (1600 2250);
PAINT ORANGE (1600 2250);
DISPLAY INVISIBLE (1600 2250);
FORCEPROP 2 LAST CDS_LOCATION C5D4
J 0
(1600 2150);
DISPLAY 0.617021 (1600 2150);
PAINT AQUA (1600 2150);
DISPLAY INVISIBLE (1600 2150);
FORCEADD CAP_A..1
(1200 2050);
FORCEPROP 1 LAST LOCATION C5D3
J 0
(1250 2150);
DISPLAY 0.617021 (1250 2150);
PAINT AQUA (1250 2150);
FORCEPROP 1 LAST VOLTAGE 4V
J 0
(1250 2050);
DISPLAY 0.617021 (1250 2050);
PAINT SKYBLUE (1250 2050);
FORCEPROP 0 LAST GROUP PWR_MLCC_CAP
J 0
(1256 1812);
DISPLAY 0.638298 (1256 1812);
PAINT BROWN (1256 1812);
DISPLAY BOTH (1256 1812);
FORCEPROP 1 LASTPIN (1200 2150) $PN 1
J 0
(1210 2130);
DISPLAY 0.617021 (1210 2130);
PAINT GREEN (1210 2130);
FORCEPROP 1 LAST VALUE 22.0UF
J 0
(1250 2100);
DISPLAY 0.617021 (1250 2100);
PAINT SKYBLUE (1250 2100);
FORCEPROP 1 LAST TOLERANCE 20%
J 0
(1250 2000);
DISPLAY 0.617021 (1250 2000);
PAINT SKYBLUE (1250 2000);
FORCEPROP 1 LAST MATERIAL X6S
J 0
(1250 1950);
DISPLAY 0.617021 (1250 1950);
PAINT SKYBLUE (1250 1950);
FORCEPROP 1 LAST PART_NUMBER E15431-004
J 0
(1250 1900);
DISPLAY 0.617021 (1250 1900);
PAINT BLUE (1250 1900);
FORCEPROP 1 LASTPIN (1200 1950) $PN 2
J 0
(1210 1930);
DISPLAY 0.617021 (1210 1930);
PAINT GREEN (1210 1930);
FORCEPROP 1 LAST PACK_TYPE 0603V
J 0
(1250 1850);
DISPLAY 0.617021 (1250 1850);
PAINT SKYBLUE (1250 1850);
FORCEPROP 2 LAST CDS_LOCATION C5D3
J 0
(1250 2150);
DISPLAY 0.617021 (1250 2150);
PAINT AQUA (1250 2150);
DISPLAY INVISIBLE (1250 2150);
FORCEPROP 2 LAST BOM_COST PROC_SOCKET
J 0
(1250 2250);
DISPLAY 1.021277 (1250 2250);
PAINT ORANGE (1250 2250);
DISPLAY INVISIBLE (1250 2250);
FORCEPROP 2 LAST CDS_LIB dev_discrete
J 0
(1200 2050);
PAINT ORANGE (1200 2050);
DISPLAY INVISIBLE (1200 2050);
FORCEPROP 2 LAST CDS_SEC 1
J 0
(1250 2250);
PAINT MONO (1250 2250);
DISPLAY INVISIBLE (1250 2250);
FORCEPROP 2 LAST $SEC 1
J 0
(1250 2250);
PAINT MONO (1250 2250);
DISPLAY INVISIBLE (1250 2250);
FORCEPROP 2 LAST ROOM PVCCIN_CPU0_DECAP_VR
J 0
(1250 2200);
DISPLAY 1.021277 (1250 2200);
PAINT ORANGE (1250 2200);
DISPLAY INVISIBLE (1250 2200);
FORCEPROP 1 LAST PATH I250
J 0
(1250 2200);
DISPLAY 0.978723 (1250 2200);
PAINT WHITE (1250 2200);
DISPLAY INVISIBLE (1250 2200);
FORCEADD CAP_A..1
(850 2050);
FORCEPROP 0 LAST GROUP PWR_MLCC_CAP
J 0
(906 1762);
DISPLAY 0.638298 (906 1762);
PAINT BROWN (906 1762);
DISPLAY BOTH (906 1762);
FORCEPROP 1 LAST LOCATION C5D2
J 0
(900 2150);
DISPLAY 0.617021 (900 2150);
PAINT AQUA (900 2150);
FORCEPROP 1 LAST VALUE 22.0UF
J 0
(900 2100);
DISPLAY 0.617021 (900 2100);
PAINT SKYBLUE (900 2100);
FORCEPROP 1 LASTPIN (850 2150) $PN 1
J 0
(860 2130);
DISPLAY 0.617021 (860 2130);
PAINT GREEN (860 2130);
FORCEPROP 1 LAST PACK_TYPE 0603V
J 0
(900 1850);
DISPLAY 0.617021 (900 1850);
PAINT SKYBLUE (900 1850);
FORCEPROP 1 LAST MATERIAL X6S
J 0
(900 1950);
DISPLAY 0.617021 (900 1950);
PAINT SKYBLUE (900 1950);
FORCEPROP 1 LAST TOLERANCE 20%
J 0
(900 2000);
DISPLAY 0.617021 (900 2000);
PAINT SKYBLUE (900 2000);
FORCEPROP 1 LAST VOLTAGE 4V
J 0
(900 2050);
DISPLAY 0.617021 (900 2050);
PAINT SKYBLUE (900 2050);
FORCEPROP 1 LASTPIN (850 1950) $PN 2
J 0
(860 1930);
DISPLAY 0.617021 (860 1930);
PAINT GREEN (860 1930);
FORCEPROP 1 LAST PART_NUMBER E15431-004
J 0
(900 1900);
DISPLAY 0.617021 (900 1900);
PAINT BLUE (900 1900);
FORCEPROP 1 LAST PATH I251
J 0
(900 2200);
DISPLAY 0.978723 (900 2200);
PAINT WHITE (900 2200);
DISPLAY INVISIBLE (900 2200);
FORCEPROP 2 LAST CDS_LOCATION C5D2
J 0
(900 2150);
DISPLAY 0.617021 (900 2150);
PAINT AQUA (900 2150);
DISPLAY INVISIBLE (900 2150);
FORCEPROP 2 LAST BOM_COST PROC_SOCKET
J 0
(900 2250);
DISPLAY 1.021277 (900 2250);
PAINT ORANGE (900 2250);
DISPLAY INVISIBLE (900 2250);
FORCEPROP 2 LAST CDS_LIB dev_discrete
J 0
(850 2050);
PAINT ORANGE (850 2050);
DISPLAY INVISIBLE (850 2050);
FORCEPROP 2 LAST CDS_SEC 1
J 0
(900 2250);
PAINT MONO (900 2250);
DISPLAY INVISIBLE (900 2250);
FORCEPROP 2 LAST $SEC 1
J 0
(900 2250);
PAINT MONO (900 2250);
DISPLAY INVISIBLE (900 2250);
FORCEPROP 2 LAST ROOM PVCCIN_CPU0_DECAP_VR
J 0
(900 2200);
DISPLAY 1.021277 (900 2200);
PAINT ORANGE (900 2200);
DISPLAY INVISIBLE (900 2200);
FORCEADD CAP_A..1
(500 2050);
FORCEPROP 1 LAST VALUE 22.0UF
J 0
(550 2100);
DISPLAY 0.617021 (550 2100);
PAINT SKYBLUE (550 2100);
FORCEPROP 0 LAST GROUP PWR_MLCC_CAP
J 0
(556 1812);
DISPLAY 0.638298 (556 1812);
PAINT BROWN (556 1812);
DISPLAY BOTH (556 1812);
FORCEPROP 1 LAST VOLTAGE 4V
J 0
(550 2050);
DISPLAY 0.617021 (550 2050);
PAINT SKYBLUE (550 2050);
FORCEPROP 1 LAST TOLERANCE 20%
J 0
(550 2000);
DISPLAY 0.617021 (550 2000);
PAINT SKYBLUE (550 2000);
FORCEPROP 1 LAST MATERIAL X6S
J 0
(550 1950);
DISPLAY 0.617021 (550 1950);
PAINT SKYBLUE (550 1950);
FORCEPROP 1 LAST PART_NUMBER E15431-004
J 0
(550 1900);
DISPLAY 0.617021 (550 1900);
PAINT BLUE (550 1900);
FORCEPROP 1 LASTPIN (500 2150) $PN 1
J 0
(510 2130);
DISPLAY 0.617021 (510 2130);
PAINT GREEN (510 2130);
FORCEPROP 1 LAST LOCATION C5D1
J 0
(550 2150);
DISPLAY 0.617021 (550 2150);
PAINT AQUA (550 2150);
FORCEPROP 1 LASTPIN (500 1950) $PN 2
J 0
(510 1930);
DISPLAY 0.617021 (510 1930);
PAINT GREEN (510 1930);
FORCEPROP 1 LAST PACK_TYPE 0603V
J 0
(550 1850);
DISPLAY 0.617021 (550 1850);
PAINT SKYBLUE (550 1850);
FORCEPROP 2 LAST CDS_LOCATION C5D1
J 0
(550 2150);
DISPLAY 0.617021 (550 2150);
PAINT AQUA (550 2150);
DISPLAY INVISIBLE (550 2150);
FORCEPROP 2 LAST BOM_COST PROC_SOCKET
J 0
(550 2250);
DISPLAY 1.021277 (550 2250);
PAINT ORANGE (550 2250);
DISPLAY INVISIBLE (550 2250);
FORCEPROP 2 LAST CDS_LIB dev_discrete
J 0
(500 2050);
PAINT ORANGE (500 2050);
DISPLAY INVISIBLE (500 2050);
FORCEPROP 2 LAST CDS_SEC 1
J 0
(550 2250);
PAINT MONO (550 2250);
DISPLAY INVISIBLE (550 2250);
FORCEPROP 2 LAST $SEC 1
J 0
(550 2250);
PAINT MONO (550 2250);
DISPLAY INVISIBLE (550 2250);
FORCEPROP 2 LAST ROOM PVCCIN_CPU0_DECAP_VR
J 0
(550 2200);
DISPLAY 1.021277 (550 2200);
PAINT ORANGE (550 2200);
DISPLAY INVISIBLE (550 2200);
FORCEPROP 1 LAST PATH I252
J 0
(550 2200);
DISPLAY 0.978723 (550 2200);
PAINT WHITE (550 2200);
DISPLAY INVISIBLE (550 2200);
FORCEADD GND..1
(1550 1700);
FORCEPROP 3 LASTPIN (1550 1750) SIG_NAME GND\g
J 0
(1560 1760);
DISPLAY 0.659574 (1560 1760);
PAINT MONO (1560 1760);
DISPLAY INVISIBLE (1560 1760);
FORCEPROP 1 LAST PATH I253
J 0
(1625 1700);
DISPLAY 0.872340 (1625 1700);
PAINT AQUA (1625 1700);
DISPLAY INVISIBLE (1625 1700);
FORCEPROP 1 LAST VOLTAGE 0
J 0
(1550 1700);
PAINT SKYBLUE (1550 1700);
DISPLAY INVISIBLE (1550 1700);
FORCEPROP 1 LAST SIZE 1B
J 0
(1625 1650);
DISPLAY 0.893617 (1625 1650);
PAINT GREEN (1625 1650);
DISPLAY INVISIBLE (1625 1650);
FORCEPROP 2 LAST CDS_LIB mstr_symbols
J 0
(1550 1700);
PAINT ORANGE (1550 1700);
DISPLAY INVISIBLE (1550 1700);
FORCEPROP 1 LAST BODY_TYPE PLUMBING
J 0
(1505 1657);
DISPLAY 0.340426 (1505 1657);
PAINT GREEN (1505 1657);
DISPLAY INVISIBLE (1505 1657);
FORCEPROP 1 LAST HDL_POWER GND
J 0
(1550 1850);
DISPLAY 0.893617 (1550 1850);
PAINT GREEN (1550 1850);
DISPLAY INVISIBLE (1550 1850);
FORCEADD PVDDQ_DEF..1
(500 2300);
FORCEPROP 3 LASTPIN (500 2250) SIG_NAME PVDDQ_DEF\g
J 0
(510 2260);
DISPLAY 0.659574 (510 2260);
PAINT MONO (510 2260);
DISPLAY INVISIBLE (510 2260);
FORCEPROP 1 LAST VOLTAGE 1.2V
J 0
(455 2257);
DISPLAY 0.340426 (455 2257);
PAINT SKYBLUE (455 2257);
DISPLAY INVISIBLE (455 2257);
FORCEPROP 2 LAST BOM_COST MEM_VRD_PVPP_DEF
J 0
(550 2400);
PAINT MONO (550 2400);
DISPLAY INVISIBLE (550 2400);
FORCEPROP 2 LAST ROOM VDDQ_DEF_PWR_VR
J 0
(725 2400);
PAINT ORANGE (725 2400);
DISPLAY INVISIBLE (725 2400);
FORCEPROP 1 LAST PATH I254
J 0
(550 2325);
DISPLAY 0.872340 (550 2325);
PAINT AQUA (550 2325);
DISPLAY INVISIBLE (550 2325);
FORCEPROP 2 LAST CDS_LIB mstr_symbols
J 0
(500 2300);
PAINT MONO (500 2300);
DISPLAY INVISIBLE (500 2300);
FORCEPROP 1 LAST BODY_TYPE PLUMBING
J 0
(455 2257);
DISPLAY 0.340426 (455 2257);
PAINT GREEN (455 2257);
DISPLAY INVISIBLE (455 2257);
FORCEPROP 1 LAST HDL_POWER PVDDQ_DEF
J 1
(500 2350);
DISPLAY 0.872340 (500 2350);
PAINT GREEN (500 2350);
DISPLAY INVISIBLE (500 2350);
FORCEADD GND..1
(1600 2750);
FORCEPROP 3 LASTPIN (1600 2800) SIG_NAME GND\g
J 0
(1610 2810);
DISPLAY 0.659574 (1610 2810);
PAINT MONO (1610 2810);
DISPLAY INVISIBLE (1610 2810);
FORCEPROP 1 LAST PATH I255
J 0
(1675 2750);
DISPLAY 0.872340 (1675 2750);
PAINT AQUA (1675 2750);
DISPLAY INVISIBLE (1675 2750);
FORCEPROP 1 LAST VOLTAGE 0
J 0
(1600 2750);
PAINT SKYBLUE (1600 2750);
DISPLAY INVISIBLE (1600 2750);
FORCEPROP 1 LAST SIZE 1B
J 0
(1675 2700);
DISPLAY 0.893617 (1675 2700);
PAINT GREEN (1675 2700);
DISPLAY INVISIBLE (1675 2700);
FORCEPROP 2 LAST CDS_LIB mstr_symbols
J 0
(1600 2750);
PAINT ORANGE (1600 2750);
DISPLAY INVISIBLE (1600 2750);
FORCEPROP 1 LAST BODY_TYPE PLUMBING
J 0
(1555 2707);
DISPLAY 0.340426 (1555 2707);
PAINT GREEN (1555 2707);
DISPLAY INVISIBLE (1555 2707);
FORCEPROP 1 LAST HDL_POWER GND
J 0
(1600 2900);
DISPLAY 0.893617 (1600 2900);
PAINT GREEN (1600 2900);
DISPLAY INVISIBLE (1600 2900);
FORCEADD PVDDQ_DEF..1
(1600 3150);
FORCEPROP 3 LASTPIN (1600 3100) SIG_NAME PVDDQ_DEF\g
J 0
(1610 3110);
DISPLAY 0.659574 (1610 3110);
PAINT MONO (1610 3110);
DISPLAY INVISIBLE (1610 3110);
FORCEPROP 1 LAST PATH I257
J 0
(1650 3175);
DISPLAY 0.872340 (1650 3175);
PAINT AQUA (1650 3175);
DISPLAY INVISIBLE (1650 3175);
FORCEPROP 1 LAST HDL_POWER PVDDQ_DEF
J 1
(1600 3200);
DISPLAY 0.872340 (1600 3200);
PAINT GREEN (1600 3200);
DISPLAY INVISIBLE (1600 3200);
FORCEPROP 1 LAST BODY_TYPE PLUMBING
J 0
(1555 3107);
DISPLAY 0.340426 (1555 3107);
PAINT GREEN (1555 3107);
DISPLAY INVISIBLE (1555 3107);
FORCEPROP 1 LAST VOLTAGE 1.2V
J 0
(1555 3107);
DISPLAY 0.340426 (1555 3107);
PAINT SKYBLUE (1555 3107);
DISPLAY INVISIBLE (1555 3107);
FORCEPROP 2 LAST BOM_COST MEM_VRD_PVPP_DEF
J 0
(1650 3250);
PAINT MONO (1650 3250);
DISPLAY INVISIBLE (1650 3250);
FORCEPROP 2 LAST ROOM VDDQ_DEF_PWR_VR
J 0
(1825 3250);
PAINT ORANGE (1825 3250);
DISPLAY INVISIBLE (1825 3250);
FORCEPROP 2 LAST CDS_LIB mstr_symbols
J 0
(1600 3150);
PAINT ORANGE (1600 3150);
DISPLAY INVISIBLE (1600 3150);
FORCEADD CAP_A..1
(-1450 2975);
FORCEPROP 1 LAST VALUE 22.0UF
J 0
(-1400 3025);
DISPLAY 0.617021 (-1400 3025);
PAINT SKYBLUE (-1400 3025);
FORCEPROP 1 LAST PART_NUMBER E15431-004
J 0
(-1400 2825);
DISPLAY 0.617021 (-1400 2825);
PAINT BLUE (-1400 2825);
FORCEPROP 1 LAST PACK_TYPE 0603V
J 0
(-1400 2775);
DISPLAY 0.617021 (-1400 2775);
PAINT SKYBLUE (-1400 2775);
FORCEPROP 0 LAST GROUP PWR_MLCC_CAP
J 0
(-1394 2737);
DISPLAY 0.638298 (-1394 2737);
PAINT BROWN (-1394 2737);
DISPLAY BOTH (-1394 2737);
FORCEPROP 1 LAST LOCATION C5D9
J 0
(-1400 3075);
DISPLAY 0.617021 (-1400 3075);
PAINT AQUA (-1400 3075);
FORCEPROP 1 LASTPIN (-1450 3075) $PN 1
J 0
(-1440 3055);
DISPLAY 0.617021 (-1440 3055);
PAINT GREEN (-1440 3055);
FORCEPROP 1 LAST VOLTAGE 4V
J 0
(-1400 2975);
DISPLAY 0.617021 (-1400 2975);
PAINT SKYBLUE (-1400 2975);
FORCEPROP 1 LAST MATERIAL X6S
J 0
(-1400 2875);
DISPLAY 0.617021 (-1400 2875);
PAINT SKYBLUE (-1400 2875);
FORCEPROP 1 LASTPIN (-1450 2875) $PN 2
J 0
(-1440 2855);
DISPLAY 0.617021 (-1440 2855);
PAINT GREEN (-1440 2855);
FORCEPROP 1 LAST TOLERANCE 20%
J 0
(-1400 2925);
DISPLAY 0.617021 (-1400 2925);
PAINT SKYBLUE (-1400 2925);
FORCEPROP 2 LAST BOM_COST PROC_SOCKET
J 0
(-1400 3175);
DISPLAY 1.021277 (-1400 3175);
PAINT ORANGE (-1400 3175);
DISPLAY INVISIBLE (-1400 3175);
FORCEPROP 2 LAST CDS_LIB dev_discrete
J 0
(-1450 2975);
PAINT ORANGE (-1450 2975);
DISPLAY INVISIBLE (-1450 2975);
FORCEPROP 2 LAST CDS_SEC 1
J 0
(-1400 3175);
PAINT MONO (-1400 3175);
DISPLAY INVISIBLE (-1400 3175);
FORCEPROP 2 LAST $SEC 1
J 0
(-1400 3175);
PAINT MONO (-1400 3175);
DISPLAY INVISIBLE (-1400 3175);
FORCEPROP 2 LAST ROOM PVCCIN_CPU0_DECAP_VR
J 0
(-1400 3125);
DISPLAY 1.021277 (-1400 3125);
PAINT ORANGE (-1400 3125);
DISPLAY INVISIBLE (-1400 3125);
FORCEPROP 1 LAST PATH I258
J 0
(-1400 3125);
DISPLAY 0.978723 (-1400 3125);
PAINT WHITE (-1400 3125);
DISPLAY INVISIBLE (-1400 3125);
FORCEPROP 2 LAST CDS_LOCATION C5D9
J 0
(-1400 3075);
DISPLAY 0.617021 (-1400 3075);
PAINT AQUA (-1400 3075);
DISPLAY INVISIBLE (-1400 3075);
FORCEADD CAP_A..1
(-1100 2975);
FORCEPROP 1 LAST PART_NUMBER E15431-004
J 0
(-1050 2825);
DISPLAY 0.617021 (-1050 2825);
PAINT BLUE (-1050 2825);
FORCEPROP 1 LAST PACK_TYPE 0603V
J 0
(-1050 2775);
DISPLAY 0.617021 (-1050 2775);
PAINT SKYBLUE (-1050 2775);
FORCEPROP 0 LAST GROUP PWR_MLCC_CAP
J 0
(-1044 2687);
DISPLAY 0.638298 (-1044 2687);
PAINT BROWN (-1044 2687);
DISPLAY BOTH (-1044 2687);
FORCEPROP 1 LAST MATERIAL X6S
J 0
(-1050 2875);
DISPLAY 0.617021 (-1050 2875);
PAINT SKYBLUE (-1050 2875);
FORCEPROP 1 LAST VOLTAGE 4V
J 0
(-1050 2975);
DISPLAY 0.617021 (-1050 2975);
PAINT SKYBLUE (-1050 2975);
FORCEPROP 1 LAST VALUE 22.0UF
J 0
(-1050 3025);
DISPLAY 0.617021 (-1050 3025);
PAINT SKYBLUE (-1050 3025);
FORCEPROP 1 LAST LOCATION C5D6
J 0
(-1050 3075);
DISPLAY 0.617021 (-1050 3075);
PAINT AQUA (-1050 3075);
FORCEPROP 1 LAST TOLERANCE 20%
J 0
(-1050 2925);
DISPLAY 0.617021 (-1050 2925);
PAINT SKYBLUE (-1050 2925);
FORCEPROP 1 LASTPIN (-1100 2875) $PN 2
J 0
(-1090 2855);
DISPLAY 0.617021 (-1090 2855);
PAINT GREEN (-1090 2855);
FORCEPROP 1 LASTPIN (-1100 3075) $PN 1
J 0
(-1090 3055);
DISPLAY 0.617021 (-1090 3055);
PAINT GREEN (-1090 3055);
FORCEPROP 2 LAST BOM_COST PROC_SOCKET
J 0
(-1050 3175);
DISPLAY 1.021277 (-1050 3175);
PAINT ORANGE (-1050 3175);
DISPLAY INVISIBLE (-1050 3175);
FORCEPROP 2 LAST CDS_LIB dev_discrete
J 0
(-1100 2975);
PAINT ORANGE (-1100 2975);
DISPLAY INVISIBLE (-1100 2975);
FORCEPROP 2 LAST CDS_SEC 1
J 0
(-1050 3175);
PAINT MONO (-1050 3175);
DISPLAY INVISIBLE (-1050 3175);
FORCEPROP 2 LAST $SEC 1
J 0
(-1050 3175);
PAINT MONO (-1050 3175);
DISPLAY INVISIBLE (-1050 3175);
FORCEPROP 2 LAST ROOM PVCCIN_CPU0_DECAP_VR
J 0
(-1050 3125);
DISPLAY 1.021277 (-1050 3125);
PAINT ORANGE (-1050 3125);
DISPLAY INVISIBLE (-1050 3125);
FORCEPROP 1 LAST PATH I259
J 0
(-1050 3125);
DISPLAY 0.978723 (-1050 3125);
PAINT WHITE (-1050 3125);
DISPLAY INVISIBLE (-1050 3125);
FORCEPROP 2 LAST CDS_LOCATION C5D6
J 0
(-1050 3075);
DISPLAY 0.617021 (-1050 3075);
PAINT AQUA (-1050 3075);
DISPLAY INVISIBLE (-1050 3075);
FORCEADD CAP_A..1
(-750 2975);
FORCEPROP 1 LAST TOLERANCE 20%
J 0
(-700 2925);
DISPLAY 0.617021 (-700 2925);
PAINT SKYBLUE (-700 2925);
FORCEPROP 1 LAST MATERIAL X6S
J 0
(-700 2875);
DISPLAY 0.617021 (-700 2875);
PAINT SKYBLUE (-700 2875);
FORCEPROP 1 LAST PART_NUMBER E15431-004
J 0
(-700 2825);
DISPLAY 0.617021 (-700 2825);
PAINT BLUE (-700 2825);
FORCEPROP 1 LASTPIN (-750 2875) $PN 2
J 0
(-740 2855);
DISPLAY 0.617021 (-740 2855);
PAINT GREEN (-740 2855);
FORCEPROP 0 LAST GROUP PWR_MLCC_CAP
J 0
(-694 2737);
DISPLAY 0.638298 (-694 2737);
PAINT BROWN (-694 2737);
DISPLAY BOTH (-694 2737);
FORCEPROP 1 LAST PACK_TYPE 0603V
J 0
(-700 2775);
DISPLAY 0.617021 (-700 2775);
PAINT SKYBLUE (-700 2775);
FORCEPROP 1 LAST LOCATION C5D7
J 0
(-700 3075);
DISPLAY 0.617021 (-700 3075);
PAINT AQUA (-700 3075);
FORCEPROP 1 LAST VOLTAGE 4V
J 0
(-700 2975);
DISPLAY 0.617021 (-700 2975);
PAINT SKYBLUE (-700 2975);
FORCEPROP 1 LASTPIN (-750 3075) $PN 1
J 0
(-740 3055);
DISPLAY 0.617021 (-740 3055);
PAINT GREEN (-740 3055);
FORCEPROP 1 LAST VALUE 22.0UF
J 0
(-700 3025);
DISPLAY 0.617021 (-700 3025);
PAINT SKYBLUE (-700 3025);
FORCEPROP 2 LAST BOM_COST PROC_SOCKET
J 0
(-700 3175);
DISPLAY 1.021277 (-700 3175);
PAINT ORANGE (-700 3175);
DISPLAY INVISIBLE (-700 3175);
FORCEPROP 2 LAST CDS_LIB dev_discrete
J 0
(-750 2975);
PAINT ORANGE (-750 2975);
DISPLAY INVISIBLE (-750 2975);
FORCEPROP 2 LAST CDS_SEC 1
J 0
(-700 3175);
PAINT MONO (-700 3175);
DISPLAY INVISIBLE (-700 3175);
FORCEPROP 2 LAST $SEC 1
J 0
(-700 3175);
PAINT MONO (-700 3175);
DISPLAY INVISIBLE (-700 3175);
FORCEPROP 2 LAST ROOM PVCCIN_CPU0_DECAP_VR
J 0
(-700 3125);
DISPLAY 1.021277 (-700 3125);
PAINT ORANGE (-700 3125);
DISPLAY INVISIBLE (-700 3125);
FORCEPROP 1 LAST PATH I260
J 0
(-700 3125);
DISPLAY 0.978723 (-700 3125);
PAINT WHITE (-700 3125);
DISPLAY INVISIBLE (-700 3125);
FORCEPROP 2 LAST CDS_LOCATION C5D7
J 0
(-700 3075);
DISPLAY 0.617021 (-700 3075);
PAINT AQUA (-700 3075);
DISPLAY INVISIBLE (-700 3075);
FORCEADD CAP_A..1
(-400 2975);
FORCEPROP 1 LAST LOCATION C5D8
J 0
(-350 3075);
DISPLAY 0.617021 (-350 3075);
PAINT AQUA (-350 3075);
FORCEPROP 1 LAST VALUE 22.0UF
J 0
(-350 3025);
DISPLAY 0.617021 (-350 3025);
PAINT SKYBLUE (-350 3025);
FORCEPROP 1 LAST PART_NUMBER E15431-004
J 0
(-350 2825);
DISPLAY 0.617021 (-350 2825);
PAINT BLUE (-350 2825);
FORCEPROP 0 LAST GROUP PWR_MLCC_CAP
J 0
(-344 2687);
DISPLAY 0.638298 (-344 2687);
PAINT BROWN (-344 2687);
DISPLAY BOTH (-344 2687);
FORCEPROP 1 LAST PACK_TYPE 0603V
J 0
(-350 2775);
DISPLAY 0.617021 (-350 2775);
PAINT SKYBLUE (-350 2775);
FORCEPROP 1 LASTPIN (-400 2875) $PN 2
J 0
(-390 2855);
DISPLAY 0.617021 (-390 2855);
PAINT GREEN (-390 2855);
FORCEPROP 1 LAST MATERIAL X6S
J 0
(-350 2875);
DISPLAY 0.617021 (-350 2875);
PAINT SKYBLUE (-350 2875);
FORCEPROP 1 LAST TOLERANCE 20%
J 0
(-350 2925);
DISPLAY 0.617021 (-350 2925);
PAINT SKYBLUE (-350 2925);
FORCEPROP 1 LASTPIN (-400 3075) $PN 1
J 0
(-390 3055);
DISPLAY 0.617021 (-390 3055);
PAINT GREEN (-390 3055);
FORCEPROP 1 LAST VOLTAGE 4V
J 0
(-350 2975);
DISPLAY 0.617021 (-350 2975);
PAINT SKYBLUE (-350 2975);
FORCEPROP 2 LAST BOM_COST PROC_SOCKET
J 0
(-350 3175);
DISPLAY 1.021277 (-350 3175);
PAINT ORANGE (-350 3175);
DISPLAY INVISIBLE (-350 3175);
FORCEPROP 2 LAST CDS_LIB dev_discrete
J 0
(-400 2975);
PAINT ORANGE (-400 2975);
DISPLAY INVISIBLE (-400 2975);
FORCEPROP 2 LAST CDS_SEC 1
J 0
(-350 3175);
PAINT MONO (-350 3175);
DISPLAY INVISIBLE (-350 3175);
FORCEPROP 2 LAST $SEC 1
J 0
(-350 3175);
PAINT MONO (-350 3175);
DISPLAY INVISIBLE (-350 3175);
FORCEPROP 2 LAST ROOM PVCCIN_CPU0_DECAP_VR
J 0
(-350 3125);
DISPLAY 1.021277 (-350 3125);
PAINT ORANGE (-350 3125);
DISPLAY INVISIBLE (-350 3125);
FORCEPROP 1 LAST PATH I261
J 0
(-350 3125);
DISPLAY 0.978723 (-350 3125);
PAINT WHITE (-350 3125);
DISPLAY INVISIBLE (-350 3125);
FORCEPROP 2 LAST CDS_LOCATION C5D8
J 0
(-350 3075);
DISPLAY 0.617021 (-350 3075);
PAINT AQUA (-350 3075);
DISPLAY INVISIBLE (-350 3075);
FORCEADD CAP_A..1
(-2150 100);
FORCEPROP 1 LAST MATERIAL X5R
J 0
(-2100 0);
DISPLAY 0.617021 (-2100 0);
PAINT SKYBLUE (-2100 0);
FORCEPROP 1 LAST TOLERANCE 20%
J 0
(-2100 50);
DISPLAY 0.617021 (-2100 50);
PAINT SKYBLUE (-2100 50);
FORCEPROP 1 LAST VOLTAGE 4V
J 0
(-2100 100);
DISPLAY 0.617021 (-2100 100);
PAINT SKYBLUE (-2100 100);
FORCEPROP 1 LAST VALUE 47UF
J 0
(-2100 150);
DISPLAY 0.617021 (-2100 150);
PAINT SKYBLUE (-2100 150);
FORCEPROP 1 LAST PACK_TYPE 0603V
J 0
(-2100 -100);
DISPLAY 0.617021 (-2100 -100);
PAINT SKYBLUE (-2100 -100);
FORCEPROP 1 LAST PART_NUMBER 602433-106
J 0
(-2100 -50);
DISPLAY 0.617021 (-2100 -50);
PAINT BLUE (-2100 -50);
FORCEPROP 1 LASTPIN (-2150 0) $PN 2
J 0
(-2140 -20);
DISPLAY 0.617021 (-2140 -20);
PAINT ORANGE (-2140 -20);
FORCEPROP 1 LASTPIN (-2150 200) $PN 1
J 0
(-2140 180);
DISPLAY 0.617021 (-2140 180);
PAINT ORANGE (-2140 180);
FORCEPROP 1 LAST LOCATION C5A1
J 0
(-2100 200);
DISPLAY 0.617021 (-2100 200);
PAINT AQUA (-2100 200);
FORCEPROP 0 LAST GROUP PWR_MLCC_CAP
J 0
(-2119 -263);
DISPLAY 0.638298 (-2119 -263);
PAINT BROWN (-2119 -263);
DISPLAY BOTH (-2119 -263);
FORCEPROP 0 LAST BOM_SS E15431-004
J 0
(-2115 -162);
DISPLAY 0.510638 (-2115 -162);
PAINT BROWN (-2115 -162);
DISPLAY BOTH (-2115 -162);
FORCEPROP 2 LAST CDS_LIB dev_discrete
J 0
(-2150 100);
PAINT ORANGE (-2150 100);
DISPLAY INVISIBLE (-2150 100);
FORCEPROP 2 LAST SEC 1
J 0
(-2100 300);
DISPLAY 0.680851 (-2100 300);
PAINT MONO (-2100 300);
DISPLAY INVISIBLE (-2100 300);
FORCEPROP 2 LAST SEC_TYPE 0603V
J 0
(-2100 300);
DISPLAY 1.021277 (-2100 300);
PAINT ORANGE (-2100 300);
DISPLAY INVISIBLE (-2100 300);
FORCEPROP 2 LAST CDS_SEC 1
J 0
(-2100 250);
PAINT ORANGE (-2100 250);
DISPLAY INVISIBLE (-2100 250);
FORCEPROP 1 LAST PATH I262
J 0
(-2100 250);
DISPLAY 0.978723 (-2100 250);
PAINT WHITE (-2100 250);
DISPLAY INVISIBLE (-2100 250);
FORCEPROP 2 LAST CDS_LOCATION C5A1
J 0
(-2100 200);
DISPLAY 0.617021 (-2100 200);
PAINT AQUA (-2100 200);
DISPLAY INVISIBLE (-2100 200);
FORCEADD CAP_A..1
(-1850 100);
FORCEPROP 1 LAST LOCATION C5A15
J 0
(-1800 200);
DISPLAY 0.617021 (-1800 200);
PAINT AQUA (-1800 200);
FORCEPROP 1 LAST TOLERANCE 20%
J 0
(-1800 50);
DISPLAY 0.617021 (-1800 50);
PAINT SKYBLUE (-1800 50);
FORCEPROP 1 LAST VOLTAGE 4V
J 0
(-1800 100);
DISPLAY 0.617021 (-1800 100);
PAINT SKYBLUE (-1800 100);
FORCEPROP 1 LAST VALUE 47UF
J 0
(-1800 150);
DISPLAY 0.617021 (-1800 150);
PAINT SKYBLUE (-1800 150);
FORCEPROP 1 LASTPIN (-1850 200) $PN 1
J 0
(-1840 180);
DISPLAY 0.617021 (-1840 180);
PAINT ORANGE (-1840 180);
FORCEPROP 1 LASTPIN (-1850 0) $PN 2
J 0
(-1840 -20);
DISPLAY 0.617021 (-1840 -20);
PAINT ORANGE (-1840 -20);
FORCEPROP 0 LAST GROUP PWR_MLCC_CAP
J 0
(-1819 -288);
DISPLAY 0.638298 (-1819 -288);
PAINT BROWN (-1819 -288);
DISPLAY BOTH (-1819 -288);
FORCEPROP 1 LAST PACK_TYPE 0603V
J 0
(-1800 -100);
DISPLAY 0.617021 (-1800 -100);
PAINT SKYBLUE (-1800 -100);
FORCEPROP 1 LAST PART_NUMBER 602433-106
J 0
(-1800 -50);
DISPLAY 0.617021 (-1800 -50);
PAINT BLUE (-1800 -50);
FORCEPROP 1 LAST MATERIAL X5R
J 0
(-1800 0);
DISPLAY 0.617021 (-1800 0);
PAINT SKYBLUE (-1800 0);
FORCEPROP 0 LAST BOM_SS E15431-004
J 0
(-1841 -227);
DISPLAY 0.510638 (-1841 -227);
PAINT BROWN (-1841 -227);
DISPLAY BOTH (-1841 -227);
FORCEPROP 2 LAST CDS_SEC 1
J 0
(-1800 250);
PAINT ORANGE (-1800 250);
DISPLAY INVISIBLE (-1800 250);
FORCEPROP 2 LAST SEC_TYPE 0603V
J 0
(-1800 300);
DISPLAY 1.021277 (-1800 300);
PAINT ORANGE (-1800 300);
DISPLAY INVISIBLE (-1800 300);
FORCEPROP 2 LAST SEC 1
J 0
(-1800 300);
DISPLAY 0.680851 (-1800 300);
PAINT MONO (-1800 300);
DISPLAY INVISIBLE (-1800 300);
FORCEPROP 2 LAST CDS_LIB dev_discrete
J 0
(-1850 100);
PAINT ORANGE (-1850 100);
DISPLAY INVISIBLE (-1850 100);
FORCEPROP 1 LAST PATH I263
J 0
(-1800 250);
DISPLAY 0.978723 (-1800 250);
PAINT WHITE (-1800 250);
DISPLAY INVISIBLE (-1800 250);
FORCEPROP 2 LAST CDS_LOCATION C5A15
J 0
(-1800 200);
DISPLAY 0.617021 (-1800 200);
PAINT AQUA (-1800 200);
DISPLAY INVISIBLE (-1800 200);
FORCEADD CAP_A..1
(-1550 100);
FORCEPROP 1 LASTPIN (-1550 0) $PN 2
J 0
(-1540 -20);
DISPLAY 0.617021 (-1540 -20);
PAINT ORANGE (-1540 -20);
FORCEPROP 1 LAST MATERIAL X5R
J 0
(-1500 0);
DISPLAY 0.617021 (-1500 0);
PAINT SKYBLUE (-1500 0);
FORCEPROP 1 LAST PART_NUMBER 602433-106
J 0
(-1500 -50);
DISPLAY 0.617021 (-1500 -50);
PAINT BLUE (-1500 -50);
FORCEPROP 1 LAST PACK_TYPE 0603V
J 0
(-1500 -100);
DISPLAY 0.617021 (-1500 -100);
PAINT SKYBLUE (-1500 -100);
FORCEPROP 1 LAST LOCATION C5A12
J 0
(-1500 200);
DISPLAY 0.617021 (-1500 200);
PAINT AQUA (-1500 200);
FORCEPROP 1 LAST VOLTAGE 4V
J 0
(-1500 100);
DISPLAY 0.617021 (-1500 100);
PAINT SKYBLUE (-1500 100);
FORCEPROP 1 LAST TOLERANCE 20%
J 0
(-1500 50);
DISPLAY 0.617021 (-1500 50);
PAINT SKYBLUE (-1500 50);
FORCEPROP 1 LASTPIN (-1550 200) $PN 1
J 0
(-1540 180);
DISPLAY 0.617021 (-1540 180);
PAINT ORANGE (-1540 180);
FORCEPROP 1 LAST VALUE 47UF
J 0
(-1500 150);
DISPLAY 0.617021 (-1500 150);
PAINT SKYBLUE (-1500 150);
FORCEPROP 0 LAST GROUP PWR_MLCC_CAP
J 0
(-1494 -263);
DISPLAY 0.638298 (-1494 -263);
PAINT BROWN (-1494 -263);
DISPLAY BOTH (-1494 -263);
FORCEPROP 0 LAST BOM_SS E15431-004
J 0
(-1534 -174);
DISPLAY 0.510638 (-1534 -174);
PAINT BROWN (-1534 -174);
DISPLAY BOTH (-1534 -174);
FORCEPROP 2 LAST CDS_LIB dev_discrete
J 0
(-1550 100);
PAINT ORANGE (-1550 100);
DISPLAY INVISIBLE (-1550 100);
FORCEPROP 2 LAST SEC 1
J 0
(-1500 300);
DISPLAY 0.680851 (-1500 300);
PAINT MONO (-1500 300);
DISPLAY INVISIBLE (-1500 300);
FORCEPROP 2 LAST SEC_TYPE 0603V
J 0
(-1500 300);
DISPLAY 1.021277 (-1500 300);
PAINT ORANGE (-1500 300);
DISPLAY INVISIBLE (-1500 300);
FORCEPROP 2 LAST CDS_SEC 1
J 0
(-1500 250);
PAINT ORANGE (-1500 250);
DISPLAY INVISIBLE (-1500 250);
FORCEPROP 1 LAST PATH I264
J 0
(-1500 250);
DISPLAY 0.978723 (-1500 250);
PAINT WHITE (-1500 250);
DISPLAY INVISIBLE (-1500 250);
FORCEPROP 2 LAST CDS_LOCATION C5A12
J 0
(-1500 200);
DISPLAY 0.617021 (-1500 200);
PAINT AQUA (-1500 200);
DISPLAY INVISIBLE (-1500 200);
FORCEADD CAP_A..1
(-1275 100);
FORCEPROP 1 LAST VALUE 47UF
J 0
(-1225 150);
DISPLAY 0.617021 (-1225 150);
PAINT SKYBLUE (-1225 150);
FORCEPROP 1 LASTPIN (-1275 200) $PN 1
J 0
(-1265 180);
DISPLAY 0.617021 (-1265 180);
PAINT ORANGE (-1265 180);
FORCEPROP 1 LAST VOLTAGE 4V
J 0
(-1225 100);
DISPLAY 0.617021 (-1225 100);
PAINT SKYBLUE (-1225 100);
FORCEPROP 1 LASTPIN (-1275 0) $PN 2
J 0
(-1265 -20);
DISPLAY 0.617021 (-1265 -20);
PAINT ORANGE (-1265 -20);
FORCEPROP 1 LAST MATERIAL X5R
J 0
(-1225 0);
DISPLAY 0.617021 (-1225 0);
PAINT SKYBLUE (-1225 0);
FORCEPROP 1 LAST TOLERANCE 20%
J 0
(-1225 50);
DISPLAY 0.617021 (-1225 50);
PAINT SKYBLUE (-1225 50);
FORCEPROP 1 LAST LOCATION C5A13
J 0
(-1225 200);
DISPLAY 0.617021 (-1225 200);
PAINT AQUA (-1225 200);
FORCEPROP 0 LAST GROUP PWR_MLCC_CAP
J 0
(-1219 -313);
DISPLAY 0.638298 (-1219 -313);
PAINT BROWN (-1219 -313);
DISPLAY BOTH (-1219 -313);
FORCEPROP 1 LAST PART_NUMBER 602433-106
J 0
(-1225 -50);
DISPLAY 0.617021 (-1225 -50);
PAINT BLUE (-1225 -50);
FORCEPROP 1 LAST PACK_TYPE 0603V
J 0
(-1225 -100);
DISPLAY 0.617021 (-1225 -100);
PAINT SKYBLUE (-1225 -100);
FORCEPROP 0 LAST BOM_SS E15431-004
J 0
(-1248 -209);
DISPLAY 0.510638 (-1248 -209);
PAINT BROWN (-1248 -209);
DISPLAY BOTH (-1248 -209);
FORCEPROP 2 LAST CDS_SEC 1
J 0
(-1225 250);
PAINT ORANGE (-1225 250);
DISPLAY INVISIBLE (-1225 250);
FORCEPROP 2 LAST SEC_TYPE 0603V
J 0
(-1225 300);
DISPLAY 1.021277 (-1225 300);
PAINT ORANGE (-1225 300);
DISPLAY INVISIBLE (-1225 300);
FORCEPROP 2 LAST SEC 1
J 0
(-1225 300);
DISPLAY 0.680851 (-1225 300);
PAINT MONO (-1225 300);
DISPLAY INVISIBLE (-1225 300);
FORCEPROP 2 LAST CDS_LIB dev_discrete
J 0
(-1275 100);
PAINT ORANGE (-1275 100);
DISPLAY INVISIBLE (-1275 100);
FORCEPROP 1 LAST PATH I265
J 0
(-1225 250);
DISPLAY 0.978723 (-1225 250);
PAINT WHITE (-1225 250);
DISPLAY INVISIBLE (-1225 250);
FORCEPROP 2 LAST CDS_LOCATION C5A13
J 0
(-1225 200);
DISPLAY 0.617021 (-1225 200);
PAINT AQUA (-1225 200);
DISPLAY INVISIBLE (-1225 200);
FORCEADD CAP_A..1
(-1000 100);
FORCEPROP 1 LAST LOCATION C5A2
J 0
(-950 200);
DISPLAY 0.617021 (-950 200);
PAINT AQUA (-950 200);
FORCEPROP 1 LAST VOLTAGE 4V
J 0
(-950 100);
DISPLAY 0.617021 (-950 100);
PAINT SKYBLUE (-950 100);
FORCEPROP 1 LASTPIN (-1000 200) $PN 1
J 0
(-990 180);
DISPLAY 0.617021 (-990 180);
PAINT ORANGE (-990 180);
FORCEPROP 1 LASTPIN (-1000 0) $PN 2
J 0
(-990 -20);
DISPLAY 0.617021 (-990 -20);
PAINT ORANGE (-990 -20);
FORCEPROP 1 LAST TOLERANCE 20%
J 0
(-950 50);
DISPLAY 0.617021 (-950 50);
PAINT SKYBLUE (-950 50);
FORCEPROP 1 LAST PACK_TYPE 0603V
J 0
(-950 -100);
DISPLAY 0.617021 (-950 -100);
PAINT SKYBLUE (-950 -100);
FORCEPROP 1 LAST PART_NUMBER 602433-106
J 0
(-950 -50);
DISPLAY 0.617021 (-950 -50);
PAINT BLUE (-950 -50);
FORCEPROP 1 LAST MATERIAL X5R
J 0
(-950 0);
DISPLAY 0.617021 (-950 0);
PAINT SKYBLUE (-950 0);
FORCEPROP 1 LAST VALUE 47UF
J 0
(-950 150);
DISPLAY 0.617021 (-950 150);
PAINT SKYBLUE (-950 150);
FORCEPROP 0 LAST GROUP PWR_MLCC_CAP
J 0
(-944 -263);
DISPLAY 0.638298 (-944 -263);
PAINT BROWN (-944 -263);
DISPLAY BOTH (-944 -263);
FORCEPROP 0 LAST BOM_SS E15431-004
J 0
(-996 -176);
DISPLAY 0.510638 (-996 -176);
PAINT BROWN (-996 -176);
DISPLAY BOTH (-996 -176);
FORCEPROP 2 LAST CDS_SEC 1
J 0
(-950 250);
PAINT ORANGE (-950 250);
DISPLAY INVISIBLE (-950 250);
FORCEPROP 2 LAST SEC_TYPE 0603V
J 0
(-950 300);
DISPLAY 1.021277 (-950 300);
PAINT ORANGE (-950 300);
DISPLAY INVISIBLE (-950 300);
FORCEPROP 2 LAST SEC 1
J 0
(-950 300);
DISPLAY 0.680851 (-950 300);
PAINT MONO (-950 300);
DISPLAY INVISIBLE (-950 300);
FORCEPROP 2 LAST CDS_LIB dev_discrete
J 0
(-1000 100);
PAINT ORANGE (-1000 100);
DISPLAY INVISIBLE (-1000 100);
FORCEPROP 1 LAST PATH I266
J 0
(-950 250);
DISPLAY 0.978723 (-950 250);
PAINT WHITE (-950 250);
DISPLAY INVISIBLE (-950 250);
FORCEPROP 2 LAST CDS_LOCATION C5A2
J 0
(-950 200);
DISPLAY 0.617021 (-950 200);
PAINT AQUA (-950 200);
DISPLAY INVISIBLE (-950 200);
FORCEADD CAP_A..1
(-700 100);
FORCEPROP 1 LAST VALUE 47UF
J 0
(-650 150);
DISPLAY 0.617021 (-650 150);
PAINT SKYBLUE (-650 150);
FORCEPROP 1 LASTPIN (-700 200) $PN 1
J 0
(-690 180);
DISPLAY 0.617021 (-690 180);
PAINT ORANGE (-690 180);
FORCEPROP 1 LAST PART_NUMBER 602433-106
J 0
(-650 -50);
DISPLAY 0.617021 (-650 -50);
PAINT BLUE (-650 -50);
FORCEPROP 1 LAST TOLERANCE 20%
J 0
(-650 50);
DISPLAY 0.617021 (-650 50);
PAINT SKYBLUE (-650 50);
FORCEPROP 1 LASTPIN (-700 0) $PN 2
J 0
(-690 -20);
DISPLAY 0.617021 (-690 -20);
PAINT ORANGE (-690 -20);
FORCEPROP 1 LAST VOLTAGE 4V
J 0
(-650 100);
DISPLAY 0.617021 (-650 100);
PAINT SKYBLUE (-650 100);
FORCEPROP 1 LAST LOCATION C5A14
J 0
(-650 200);
DISPLAY 0.617021 (-650 200);
PAINT AQUA (-650 200);
FORCEPROP 1 LAST MATERIAL X5R
J 0
(-650 0);
DISPLAY 0.617021 (-650 0);
PAINT SKYBLUE (-650 0);
FORCEPROP 1 LAST PACK_TYPE 0603V
J 0
(-650 -100);
DISPLAY 0.617021 (-650 -100);
PAINT SKYBLUE (-650 -100);
FORCEPROP 0 LAST GROUP PWR_MLCC_CAP
J 0
(-644 -313);
DISPLAY 0.638298 (-644 -313);
PAINT BROWN (-644 -313);
DISPLAY BOTH (-644 -313);
FORCEPROP 0 LAST BOM_SS E15431-004
J 0
(-708 -235);
DISPLAY 0.510638 (-708 -235);
PAINT BROWN (-708 -235);
DISPLAY BOTH (-708 -235);
FORCEPROP 2 LAST CDS_LIB dev_discrete
J 0
(-700 100);
PAINT ORANGE (-700 100);
DISPLAY INVISIBLE (-700 100);
FORCEPROP 2 LAST SEC 1
J 0
(-650 300);
DISPLAY 0.680851 (-650 300);
PAINT MONO (-650 300);
DISPLAY INVISIBLE (-650 300);
FORCEPROP 2 LAST SEC_TYPE 0603V
J 0
(-650 300);
DISPLAY 1.021277 (-650 300);
PAINT ORANGE (-650 300);
DISPLAY INVISIBLE (-650 300);
FORCEPROP 2 LAST CDS_SEC 1
J 0
(-650 250);
PAINT ORANGE (-650 250);
DISPLAY INVISIBLE (-650 250);
FORCEPROP 1 LAST PATH I267
J 0
(-650 250);
DISPLAY 0.978723 (-650 250);
PAINT WHITE (-650 250);
DISPLAY INVISIBLE (-650 250);
FORCEPROP 2 LAST CDS_LOCATION C5A14
J 0
(-650 200);
DISPLAY 0.617021 (-650 200);
PAINT AQUA (-650 200);
DISPLAY INVISIBLE (-650 200);
FORCEADD CAP_A..1
(-400 100);
FORCEPROP 1 LAST MATERIAL X5R
J 0
(-350 0);
DISPLAY 0.617021 (-350 0);
PAINT SKYBLUE (-350 0);
FORCEPROP 1 LAST LOCATION C5A6
J 0
(-350 200);
DISPLAY 0.617021 (-350 200);
PAINT AQUA (-350 200);
FORCEPROP 1 LAST TOLERANCE 20%
J 0
(-350 50);
DISPLAY 0.617021 (-350 50);
PAINT SKYBLUE (-350 50);
FORCEPROP 1 LAST VALUE 47UF
J 0
(-350 150);
DISPLAY 0.617021 (-350 150);
PAINT SKYBLUE (-350 150);
FORCEPROP 1 LAST VOLTAGE 4V
J 0
(-350 100);
DISPLAY 0.617021 (-350 100);
PAINT SKYBLUE (-350 100);
FORCEPROP 1 LAST PACK_TYPE 0603V
J 0
(-350 -100);
DISPLAY 0.617021 (-350 -100);
PAINT SKYBLUE (-350 -100);
FORCEPROP 1 LAST PART_NUMBER 602433-106
J 0
(-350 -50);
DISPLAY 0.617021 (-350 -50);
PAINT BLUE (-350 -50);
FORCEPROP 1 LASTPIN (-400 0) $PN 2
J 0
(-390 -20);
DISPLAY 0.617021 (-390 -20);
PAINT ORANGE (-390 -20);
FORCEPROP 1 LASTPIN (-400 200) $PN 1
J 0
(-390 180);
DISPLAY 0.617021 (-390 180);
PAINT ORANGE (-390 180);
FORCEPROP 0 LAST GROUP PWR_MLCC_CAP
J 0
(-344 -263);
DISPLAY 0.638298 (-344 -263);
PAINT BROWN (-344 -263);
DISPLAY BOTH (-344 -263);
FORCEPROP 0 LAST BOM_SS E15431-004
J 0
(-405 -180);
DISPLAY 0.510638 (-405 -180);
PAINT BROWN (-405 -180);
DISPLAY BOTH (-405 -180);
FORCEPROP 1 LAST PATH I268
J 0
(-350 250);
DISPLAY 0.978723 (-350 250);
PAINT WHITE (-350 250);
DISPLAY INVISIBLE (-350 250);
FORCEPROP 2 LAST SEC 1
J 0
(-350 300);
DISPLAY 0.680851 (-350 300);
PAINT MONO (-350 300);
DISPLAY INVISIBLE (-350 300);
FORCEPROP 2 LAST SEC_TYPE 0603V
J 0
(-350 300);
DISPLAY 1.021277 (-350 300);
PAINT ORANGE (-350 300);
DISPLAY INVISIBLE (-350 300);
FORCEPROP 2 LAST CDS_LOCATION C5A6
J 0
(-350 200);
DISPLAY 0.617021 (-350 200);
PAINT AQUA (-350 200);
DISPLAY INVISIBLE (-350 200);
FORCEPROP 2 LAST CDS_LIB dev_discrete
J 0
(-400 100);
PAINT ORANGE (-400 100);
DISPLAY INVISIBLE (-400 100);
FORCEPROP 2 LAST CDS_SEC 1
J 0
(-350 250);
PAINT ORANGE (-350 250);
DISPLAY INVISIBLE (-350 250);
FORCEADD CAP_A..1
(-125 100);
FORCEPROP 1 LASTPIN (-125 0) $PN 2
J 0
(-115 -20);
DISPLAY 0.617021 (-115 -20);
PAINT ORANGE (-115 -20);
FORCEPROP 1 LAST PART_NUMBER 602433-106
J 0
(-75 -50);
DISPLAY 0.617021 (-75 -50);
PAINT BLUE (-75 -50);
FORCEPROP 1 LAST PACK_TYPE 0603V
J 0
(-75 -100);
DISPLAY 0.617021 (-75 -100);
PAINT SKYBLUE (-75 -100);
FORCEPROP 1 LASTPIN (-125 200) $PN 1
J 0
(-115 180);
DISPLAY 0.617021 (-115 180);
PAINT ORANGE (-115 180);
FORCEPROP 1 LAST MATERIAL X5R
J 0
(-75 0);
DISPLAY 0.617021 (-75 0);
PAINT SKYBLUE (-75 0);
FORCEPROP 1 LAST TOLERANCE 20%
J 0
(-75 50);
DISPLAY 0.617021 (-75 50);
PAINT SKYBLUE (-75 50);
FORCEPROP 1 LAST VOLTAGE 4V
J 0
(-75 100);
DISPLAY 0.617021 (-75 100);
PAINT SKYBLUE (-75 100);
FORCEPROP 1 LAST VALUE 47UF
J 0
(-75 150);
DISPLAY 0.617021 (-75 150);
PAINT SKYBLUE (-75 150);
FORCEPROP 1 LAST LOCATION C5A7
J 0
(-75 200);
DISPLAY 0.617021 (-75 200);
PAINT AQUA (-75 200);
FORCEPROP 0 LAST GROUP PWR_MLCC_CAP
J 0
(-94 -313);
DISPLAY 0.638298 (-94 -313);
PAINT BROWN (-94 -313);
DISPLAY BOTH (-94 -313);
FORCEPROP 0 LAST BOM_SS E15431-004
J 0
(-106 -215);
DISPLAY 0.510638 (-106 -215);
PAINT BROWN (-106 -215);
DISPLAY BOTH (-106 -215);
FORCEPROP 2 LAST CDS_LIB dev_discrete
J 0
(-125 100);
PAINT ORANGE (-125 100);
DISPLAY INVISIBLE (-125 100);
FORCEPROP 2 LAST SEC 1
J 0
(-75 300);
DISPLAY 0.680851 (-75 300);
PAINT MONO (-75 300);
DISPLAY INVISIBLE (-75 300);
FORCEPROP 2 LAST SEC_TYPE 0603V
J 0
(-75 300);
DISPLAY 1.021277 (-75 300);
PAINT ORANGE (-75 300);
DISPLAY INVISIBLE (-75 300);
FORCEPROP 2 LAST CDS_SEC 1
J 0
(-75 250);
PAINT ORANGE (-75 250);
DISPLAY INVISIBLE (-75 250);
FORCEPROP 1 LAST PATH I269
J 0
(-75 250);
DISPLAY 0.978723 (-75 250);
PAINT WHITE (-75 250);
DISPLAY INVISIBLE (-75 250);
FORCEPROP 2 LAST CDS_LOCATION C5A7
J 0
(-75 200);
DISPLAY 0.617021 (-75 200);
PAINT AQUA (-75 200);
DISPLAY INVISIBLE (-75 200);
FORCEADD CAP_A..1
(200 100);
FORCEPROP 1 LAST VALUE 47UF
J 0
(250 150);
DISPLAY 0.617021 (250 150);
PAINT SKYBLUE (250 150);
FORCEPROP 1 LAST PART_NUMBER 602433-106
J 0
(250 -50);
DISPLAY 0.617021 (250 -50);
PAINT BLUE (250 -50);
FORCEPROP 1 LAST MATERIAL X5R
J 0
(250 0);
DISPLAY 0.617021 (250 0);
PAINT SKYBLUE (250 0);
FORCEPROP 1 LAST TOLERANCE 20%
J 0
(250 50);
DISPLAY 0.617021 (250 50);
PAINT SKYBLUE (250 50);
FORCEPROP 1 LAST VOLTAGE 4V
J 0
(250 100);
DISPLAY 0.617021 (250 100);
PAINT SKYBLUE (250 100);
FORCEPROP 1 LASTPIN (200 200) $PN 1
J 0
(210 180);
DISPLAY 0.617021 (210 180);
PAINT ORANGE (210 180);
FORCEPROP 1 LAST LOCATION C5A3
J 0
(250 200);
DISPLAY 0.617021 (250 200);
PAINT AQUA (250 200);
FORCEPROP 1 LASTPIN (200 0) $PN 2
J 0
(210 -20);
DISPLAY 0.617021 (210 -20);
PAINT ORANGE (210 -20);
FORCEPROP 1 LAST PACK_TYPE 0603V
J 0
(250 -100);
DISPLAY 0.617021 (250 -100);
PAINT SKYBLUE (250 -100);
FORCEPROP 0 LAST GROUP PWR_MLCC_CAP
J 0
(256 -263);
DISPLAY 0.638298 (256 -263);
PAINT BROWN (256 -263);
DISPLAY BOTH (256 -263);
FORCEPROP 0 LAST BOM_SS E15431-004
J 0
(210 -181);
DISPLAY 0.510638 (210 -181);
PAINT BROWN (210 -181);
DISPLAY BOTH (210 -181);
FORCEPROP 2 LAST CDS_LIB dev_discrete
J 0
(200 100);
PAINT ORANGE (200 100);
DISPLAY INVISIBLE (200 100);
FORCEPROP 2 LAST SEC 1
J 0
(250 300);
DISPLAY 0.680851 (250 300);
PAINT MONO (250 300);
DISPLAY INVISIBLE (250 300);
FORCEPROP 2 LAST SEC_TYPE 0603V
J 0
(250 300);
DISPLAY 1.021277 (250 300);
PAINT ORANGE (250 300);
DISPLAY INVISIBLE (250 300);
FORCEPROP 2 LAST CDS_SEC 1
J 0
(250 250);
PAINT ORANGE (250 250);
DISPLAY INVISIBLE (250 250);
FORCEPROP 1 LAST PATH I270
J 0
(250 250);
DISPLAY 0.978723 (250 250);
PAINT WHITE (250 250);
DISPLAY INVISIBLE (250 250);
FORCEPROP 2 LAST CDS_LOCATION C5A3
J 0
(250 200);
DISPLAY 0.617021 (250 200);
PAINT AQUA (250 200);
DISPLAY INVISIBLE (250 200);
FORCEADD CAP_A..1
(500 100);
FORCEPROP 1 LAST VALUE 47UF
J 0
(550 150);
DISPLAY 0.617021 (550 150);
PAINT SKYBLUE (550 150);
FORCEPROP 1 LAST PACK_TYPE 0603V
J 0
(550 -100);
DISPLAY 0.617021 (550 -100);
PAINT SKYBLUE (550 -100);
FORCEPROP 1 LAST PART_NUMBER 602433-106
J 0
(550 -50);
DISPLAY 0.617021 (550 -50);
PAINT BLUE (550 -50);
FORCEPROP 1 LAST VOLTAGE 4V
J 0
(550 100);
DISPLAY 0.617021 (550 100);
PAINT SKYBLUE (550 100);
FORCEPROP 1 LASTPIN (500 200) $PN 1
J 0
(510 180);
DISPLAY 0.617021 (510 180);
PAINT ORANGE (510 180);
FORCEPROP 1 LASTPIN (500 0) $PN 2
J 0
(510 -20);
DISPLAY 0.617021 (510 -20);
PAINT ORANGE (510 -20);
FORCEPROP 1 LAST MATERIAL X5R
J 0
(550 0);
DISPLAY 0.617021 (550 0);
PAINT SKYBLUE (550 0);
FORCEPROP 1 LAST TOLERANCE 20%
J 0
(550 50);
DISPLAY 0.617021 (550 50);
PAINT SKYBLUE (550 50);
FORCEPROP 1 LAST LOCATION C5A8
J 0
(550 200);
DISPLAY 0.617021 (550 200);
PAINT AQUA (550 200);
FORCEPROP 0 LAST GROUP PWR_MLCC_CAP
J 0
(531 -313);
DISPLAY 0.638298 (531 -313);
PAINT BROWN (531 -313);
DISPLAY BOTH (531 -313);
FORCEPROP 0 LAST BOM_SS E15431-004
J 0
(501 -233);
DISPLAY 0.510638 (501 -233);
PAINT BROWN (501 -233);
DISPLAY BOTH (501 -233);
FORCEPROP 2 LAST CDS_SEC 1
J 0
(550 250);
PAINT ORANGE (550 250);
DISPLAY INVISIBLE (550 250);
FORCEPROP 2 LAST SEC_TYPE 0603V
J 0
(550 300);
DISPLAY 1.021277 (550 300);
PAINT ORANGE (550 300);
DISPLAY INVISIBLE (550 300);
FORCEPROP 2 LAST SEC 1
J 0
(550 300);
DISPLAY 0.680851 (550 300);
PAINT MONO (550 300);
DISPLAY INVISIBLE (550 300);
FORCEPROP 2 LAST CDS_LIB dev_discrete
J 0
(500 100);
PAINT ORANGE (500 100);
DISPLAY INVISIBLE (500 100);
FORCEPROP 1 LAST PATH I271
J 0
(550 250);
DISPLAY 0.978723 (550 250);
PAINT WHITE (550 250);
DISPLAY INVISIBLE (550 250);
FORCEPROP 2 LAST CDS_LOCATION C5A8
J 0
(550 200);
DISPLAY 0.617021 (550 200);
PAINT AQUA (550 200);
DISPLAY INVISIBLE (550 200);
FORCEADD CAP_A..1
(800 100);
FORCEPROP 1 LAST VALUE 47UF
J 0
(850 150);
DISPLAY 0.617021 (850 150);
PAINT SKYBLUE (850 150);
FORCEPROP 1 LAST LOCATION C5A9
J 0
(850 200);
DISPLAY 0.617021 (850 200);
PAINT AQUA (850 200);
FORCEPROP 1 LAST PART_NUMBER 602433-106
J 0
(850 -50);
DISPLAY 0.617021 (850 -50);
PAINT BLUE (850 -50);
FORCEPROP 1 LASTPIN (800 0) $PN 2
J 0
(810 -20);
DISPLAY 0.617021 (810 -20);
PAINT ORANGE (810 -20);
FORCEPROP 1 LAST PACK_TYPE 0603V
J 0
(850 -100);
DISPLAY 0.617021 (850 -100);
PAINT SKYBLUE (850 -100);
FORCEPROP 1 LAST TOLERANCE 20%
J 0
(850 50);
DISPLAY 0.617021 (850 50);
PAINT SKYBLUE (850 50);
FORCEPROP 1 LAST MATERIAL X5R
J 0
(850 0);
DISPLAY 0.617021 (850 0);
PAINT SKYBLUE (850 0);
FORCEPROP 1 LASTPIN (800 200) $PN 1
J 0
(810 180);
DISPLAY 0.617021 (810 180);
PAINT ORANGE (810 180);
FORCEPROP 1 LAST VOLTAGE 4V
J 0
(850 100);
DISPLAY 0.617021 (850 100);
PAINT SKYBLUE (850 100);
FORCEPROP 0 LAST GROUP PWR_MLCC_CAP
J 0
(856 -263);
DISPLAY 0.638298 (856 -263);
PAINT BROWN (856 -263);
DISPLAY BOTH (856 -263);
FORCEPROP 0 LAST BOM_SS E15431-004
J 0
(812 -160);
DISPLAY 0.510638 (812 -160);
PAINT BROWN (812 -160);
DISPLAY BOTH (812 -160);
FORCEPROP 2 LAST CDS_LIB dev_discrete
J 0
(800 100);
PAINT ORANGE (800 100);
DISPLAY INVISIBLE (800 100);
FORCEPROP 2 LAST SEC 1
J 0
(850 300);
DISPLAY 0.680851 (850 300);
PAINT MONO (850 300);
DISPLAY INVISIBLE (850 300);
FORCEPROP 2 LAST SEC_TYPE 0603V
J 0
(850 300);
DISPLAY 1.021277 (850 300);
PAINT ORANGE (850 300);
DISPLAY INVISIBLE (850 300);
FORCEPROP 2 LAST CDS_SEC 1
J 0
(850 250);
PAINT ORANGE (850 250);
DISPLAY INVISIBLE (850 250);
FORCEPROP 1 LAST PATH I272
J 0
(850 250);
DISPLAY 0.978723 (850 250);
PAINT WHITE (850 250);
DISPLAY INVISIBLE (850 250);
FORCEPROP 2 LAST CDS_LOCATION C5A9
J 0
(850 200);
DISPLAY 0.617021 (850 200);
PAINT AQUA (850 200);
DISPLAY INVISIBLE (850 200);
FORCEADD CAP_A..1
(1075 100);
FORCEPROP 1 LAST PACK_TYPE 0603V
J 0
(1125 -100);
DISPLAY 0.617021 (1125 -100);
PAINT SKYBLUE (1125 -100);
FORCEPROP 1 LAST PART_NUMBER 602433-106
J 0
(1125 -50);
DISPLAY 0.617021 (1125 -50);
PAINT BLUE (1125 -50);
FORCEPROP 1 LAST LOCATION C5A16
J 0
(1125 200);
DISPLAY 0.617021 (1125 200);
PAINT AQUA (1125 200);
FORCEPROP 1 LAST TOLERANCE 20%
J 0
(1125 50);
DISPLAY 0.617021 (1125 50);
PAINT SKYBLUE (1125 50);
FORCEPROP 1 LAST MATERIAL X5R
J 0
(1125 0);
DISPLAY 0.617021 (1125 0);
PAINT SKYBLUE (1125 0);
FORCEPROP 1 LASTPIN (1075 0) $PN 2
J 0
(1085 -20);
DISPLAY 0.617021 (1085 -20);
PAINT ORANGE (1085 -20);
FORCEPROP 1 LASTPIN (1075 200) $PN 1
J 0
(1085 180);
DISPLAY 0.617021 (1085 180);
PAINT ORANGE (1085 180);
FORCEPROP 1 LAST VALUE 47UF
J 0
(1125 150);
DISPLAY 0.617021 (1125 150);
PAINT SKYBLUE (1125 150);
FORCEPROP 1 LAST VOLTAGE 4V
J 0
(1125 100);
DISPLAY 0.617021 (1125 100);
PAINT SKYBLUE (1125 100);
FORCEPROP 0 LAST GROUP PWR_MLCC_CAP
J 0
(1131 -313);
DISPLAY 0.638298 (1131 -313);
PAINT BROWN (1131 -313);
DISPLAY BOTH (1131 -313);
FORCEPROP 0 LAST BOM_SS E15431-004
J 0
(1099 -232);
DISPLAY 0.510638 (1099 -232);
PAINT BROWN (1099 -232);
DISPLAY BOTH (1099 -232);
FORCEPROP 2 LAST CDS_LIB dev_discrete
J 0
(1075 100);
PAINT ORANGE (1075 100);
DISPLAY INVISIBLE (1075 100);
FORCEPROP 2 LAST SEC 1
J 0
(1125 300);
DISPLAY 0.680851 (1125 300);
PAINT MONO (1125 300);
DISPLAY INVISIBLE (1125 300);
FORCEPROP 2 LAST SEC_TYPE 0603V
J 0
(1125 300);
DISPLAY 1.021277 (1125 300);
PAINT ORANGE (1125 300);
DISPLAY INVISIBLE (1125 300);
FORCEPROP 2 LAST CDS_SEC 1
J 0
(1125 250);
PAINT ORANGE (1125 250);
DISPLAY INVISIBLE (1125 250);
FORCEPROP 1 LAST PATH I273
J 0
(1125 250);
DISPLAY 0.978723 (1125 250);
PAINT WHITE (1125 250);
DISPLAY INVISIBLE (1125 250);
FORCEPROP 2 LAST CDS_LOCATION C5A16
J 0
(1125 200);
DISPLAY 0.617021 (1125 200);
PAINT AQUA (1125 200);
DISPLAY INVISIBLE (1125 200);
FORCEADD CAP_A..1
(1350 100);
FORCEPROP 0 LAST GROUP PWR_MLCC_CAP
J 0
(1406 -263);
DISPLAY 0.638298 (1406 -263);
PAINT BROWN (1406 -263);
DISPLAY BOTH (1406 -263);
FORCEPROP 1 LAST VOLTAGE 4V
J 0
(1400 100);
DISPLAY 0.617021 (1400 100);
PAINT SKYBLUE (1400 100);
FORCEPROP 1 LAST VALUE 47UF
J 0
(1400 150);
DISPLAY 0.617021 (1400 150);
PAINT SKYBLUE (1400 150);
FORCEPROP 1 LASTPIN (1350 200) $PN 1
J 0
(1360 180);
DISPLAY 0.617021 (1360 180);
PAINT ORANGE (1360 180);
FORCEPROP 1 LASTPIN (1350 0) $PN 2
J 0
(1360 -20);
DISPLAY 0.617021 (1360 -20);
PAINT ORANGE (1360 -20);
FORCEPROP 1 LAST TOLERANCE 20%
J 0
(1400 50);
DISPLAY 0.617021 (1400 50);
PAINT SKYBLUE (1400 50);
FORCEPROP 1 LAST LOCATION C5A4
J 0
(1400 200);
DISPLAY 0.617021 (1400 200);
PAINT AQUA (1400 200);
FORCEPROP 1 LAST PART_NUMBER 602433-106
J 0
(1400 -50);
DISPLAY 0.617021 (1400 -50);
PAINT BLUE (1400 -50);
FORCEPROP 1 LAST MATERIAL X5R
J 0
(1400 0);
DISPLAY 0.617021 (1400 0);
PAINT SKYBLUE (1400 0);
FORCEPROP 1 LAST PACK_TYPE 0603V
J 0
(1400 -100);
DISPLAY 0.617021 (1400 -100);
PAINT SKYBLUE (1400 -100);
FORCEPROP 0 LAST BOM_SS E15431-004
J 0
(1367 -164);
DISPLAY 0.510638 (1367 -164);
PAINT BROWN (1367 -164);
DISPLAY BOTH (1367 -164);
FORCEPROP 2 LAST CDS_SEC 1
J 0
(1400 250);
PAINT ORANGE (1400 250);
DISPLAY INVISIBLE (1400 250);
FORCEPROP 2 LAST SEC_TYPE 0603V
J 0
(1400 300);
DISPLAY 1.021277 (1400 300);
PAINT ORANGE (1400 300);
DISPLAY INVISIBLE (1400 300);
FORCEPROP 2 LAST SEC 1
J 0
(1400 300);
DISPLAY 0.680851 (1400 300);
PAINT MONO (1400 300);
DISPLAY INVISIBLE (1400 300);
FORCEPROP 2 LAST CDS_LIB dev_discrete
J 0
(1350 100);
PAINT ORANGE (1350 100);
DISPLAY INVISIBLE (1350 100);
FORCEPROP 1 LAST PATH I274
J 0
(1400 250);
DISPLAY 0.978723 (1400 250);
PAINT WHITE (1400 250);
DISPLAY INVISIBLE (1400 250);
FORCEPROP 2 LAST CDS_LOCATION C5A4
J 0
(1400 200);
DISPLAY 0.617021 (1400 200);
PAINT AQUA (1400 200);
DISPLAY INVISIBLE (1400 200);
FORCEADD CAP_A..1
(1650 100);
FORCEPROP 0 LAST GROUP PWR_MLCC_CAP
J 0
(1706 -313);
DISPLAY 0.638298 (1706 -313);
PAINT BROWN (1706 -313);
DISPLAY BOTH (1706 -313);
FORCEPROP 1 LASTPIN (1650 0) $PN 2
J 0
(1660 -20);
DISPLAY 0.617021 (1660 -20);
PAINT ORANGE (1660 -20);
FORCEPROP 1 LASTPIN (1650 200) $PN 1
J 0
(1660 180);
DISPLAY 0.617021 (1660 180);
PAINT ORANGE (1660 180);
FORCEPROP 1 LAST PACK_TYPE 0603V
J 0
(1700 -100);
DISPLAY 0.617021 (1700 -100);
PAINT SKYBLUE (1700 -100);
FORCEPROP 1 LAST PART_NUMBER 602433-106
J 0
(1700 -50);
DISPLAY 0.617021 (1700 -50);
PAINT BLUE (1700 -50);
FORCEPROP 1 LAST MATERIAL X5R
J 0
(1700 0);
DISPLAY 0.617021 (1700 0);
PAINT SKYBLUE (1700 0);
FORCEPROP 1 LAST TOLERANCE 20%
J 0
(1700 50);
DISPLAY 0.617021 (1700 50);
PAINT SKYBLUE (1700 50);
FORCEPROP 1 LAST VOLTAGE 4V
J 0
(1700 100);
DISPLAY 0.617021 (1700 100);
PAINT SKYBLUE (1700 100);
FORCEPROP 1 LAST VALUE 47UF
J 0
(1700 150);
DISPLAY 0.617021 (1700 150);
PAINT SKYBLUE (1700 150);
FORCEPROP 1 LAST LOCATION C5A17
J 0
(1700 200);
DISPLAY 0.617021 (1700 200);
PAINT AQUA (1700 200);
FORCEPROP 0 LAST BOM_SS E15431-004
J 0
(1664 -231);
DISPLAY 0.510638 (1664 -231);
PAINT BROWN (1664 -231);
DISPLAY BOTH (1664 -231);
FORCEPROP 2 LAST CDS_LIB dev_discrete
J 0
(1650 100);
PAINT ORANGE (1650 100);
DISPLAY INVISIBLE (1650 100);
FORCEPROP 2 LAST SEC 1
J 0
(1700 300);
DISPLAY 0.680851 (1700 300);
PAINT MONO (1700 300);
DISPLAY INVISIBLE (1700 300);
FORCEPROP 2 LAST SEC_TYPE 0603V
J 0
(1700 300);
DISPLAY 1.021277 (1700 300);
PAINT ORANGE (1700 300);
DISPLAY INVISIBLE (1700 300);
FORCEPROP 2 LAST CDS_SEC 1
J 0
(1700 250);
PAINT ORANGE (1700 250);
DISPLAY INVISIBLE (1700 250);
FORCEPROP 1 LAST PATH I275
J 0
(1700 250);
DISPLAY 0.978723 (1700 250);
PAINT WHITE (1700 250);
DISPLAY INVISIBLE (1700 250);
FORCEPROP 2 LAST CDS_LOCATION C5A17
J 0
(1700 200);
DISPLAY 0.617021 (1700 200);
PAINT AQUA (1700 200);
DISPLAY INVISIBLE (1700 200);
FORCEADD CAP_A..1
(1950 100);
FORCEPROP 0 LAST GROUP PWR_MLCC_CAP
J 0
(2006 -263);
DISPLAY 0.638298 (2006 -263);
PAINT BROWN (2006 -263);
DISPLAY BOTH (2006 -263);
FORCEPROP 1 LAST PART_NUMBER 602433-106
J 0
(2000 -50);
DISPLAY 0.617021 (2000 -50);
PAINT BLUE (2000 -50);
FORCEPROP 1 LAST LOCATION C5A18
J 0
(2000 200);
DISPLAY 0.617021 (2000 200);
PAINT AQUA (2000 200);
FORCEPROP 1 LAST VOLTAGE 4V
J 0
(2000 100);
DISPLAY 0.617021 (2000 100);
PAINT SKYBLUE (2000 100);
FORCEPROP 1 LAST VALUE 47UF
J 0
(2000 150);
DISPLAY 0.617021 (2000 150);
PAINT SKYBLUE (2000 150);
FORCEPROP 1 LASTPIN (1950 200) $PN 1
J 0
(1960 180);
DISPLAY 0.617021 (1960 180);
PAINT ORANGE (1960 180);
FORCEPROP 1 LASTPIN (1950 0) $PN 2
J 0
(1960 -20);
DISPLAY 0.617021 (1960 -20);
PAINT ORANGE (1960 -20);
FORCEPROP 1 LAST MATERIAL X5R
J 0
(2000 0);
DISPLAY 0.617021 (2000 0);
PAINT SKYBLUE (2000 0);
FORCEPROP 1 LAST TOLERANCE 20%
J 0
(2000 50);
DISPLAY 0.617021 (2000 50);
PAINT SKYBLUE (2000 50);
FORCEPROP 1 LAST PACK_TYPE 0603V
J 0
(2000 -100);
DISPLAY 0.617021 (2000 -100);
PAINT SKYBLUE (2000 -100);
FORCEPROP 0 LAST BOM_SS E15431-004
J 0
(1981 -166);
DISPLAY 0.510638 (1981 -166);
PAINT BROWN (1981 -166);
DISPLAY BOTH (1981 -166);
FORCEPROP 2 LAST CDS_SEC 1
J 0
(2000 250);
PAINT ORANGE (2000 250);
DISPLAY INVISIBLE (2000 250);
FORCEPROP 2 LAST SEC_TYPE 0603V
J 0
(2000 300);
DISPLAY 1.021277 (2000 300);
PAINT ORANGE (2000 300);
DISPLAY INVISIBLE (2000 300);
FORCEPROP 2 LAST SEC 1
J 0
(2000 300);
DISPLAY 0.680851 (2000 300);
PAINT MONO (2000 300);
DISPLAY INVISIBLE (2000 300);
FORCEPROP 2 LAST CDS_LIB dev_discrete
J 0
(1950 100);
PAINT ORANGE (1950 100);
DISPLAY INVISIBLE (1950 100);
FORCEPROP 1 LAST PATH I276
J 0
(2000 250);
DISPLAY 0.978723 (2000 250);
PAINT WHITE (2000 250);
DISPLAY INVISIBLE (2000 250);
FORCEPROP 2 LAST CDS_LOCATION C5A18
J 0
(2000 200);
DISPLAY 0.617021 (2000 200);
PAINT AQUA (2000 200);
DISPLAY INVISIBLE (2000 200);
FORCEADD CAP_A..1
(2225 100);
FORCEPROP 1 LAST PART_NUMBER 602433-106
J 0
(2275 -50);
DISPLAY 0.617021 (2275 -50);
PAINT BLUE (2275 -50);
FORCEPROP 1 LAST LOCATION C5A19
J 0
(2275 200);
DISPLAY 0.617021 (2275 200);
PAINT AQUA (2275 200);
FORCEPROP 1 LAST VALUE 47UF
J 0
(2275 150);
DISPLAY 0.617021 (2275 150);
PAINT SKYBLUE (2275 150);
FORCEPROP 1 LAST VOLTAGE 4V
J 0
(2275 100);
DISPLAY 0.617021 (2275 100);
PAINT SKYBLUE (2275 100);
FORCEPROP 1 LASTPIN (2225 200) $PN 1
J 0
(2235 180);
DISPLAY 0.617021 (2235 180);
PAINT ORANGE (2235 180);
FORCEPROP 1 LASTPIN (2225 0) $PN 2
J 0
(2235 -20);
DISPLAY 0.617021 (2235 -20);
PAINT ORANGE (2235 -20);
FORCEPROP 1 LAST MATERIAL X5R
J 0
(2275 0);
DISPLAY 0.617021 (2275 0);
PAINT SKYBLUE (2275 0);
FORCEPROP 1 LAST TOLERANCE 20%
J 0
(2275 50);
DISPLAY 0.617021 (2275 50);
PAINT SKYBLUE (2275 50);
FORCEPROP 1 LAST PACK_TYPE 0603V
J 0
(2275 -100);
DISPLAY 0.617021 (2275 -100);
PAINT SKYBLUE (2275 -100);
FORCEPROP 0 LAST GROUP PWR_MLCC_CAP
J 0
(2281 -313);
DISPLAY 0.638298 (2281 -313);
PAINT BROWN (2281 -313);
DISPLAY BOTH (2281 -313);
FORCEPROP 0 LAST BOM_SS E15431-004
J 0
(2240 -212);
DISPLAY 0.510638 (2240 -212);
PAINT BROWN (2240 -212);
DISPLAY BOTH (2240 -212);
FORCEPROP 1 LAST PATH I277
J 0
(2275 250);
DISPLAY 0.978723 (2275 250);
PAINT WHITE (2275 250);
DISPLAY INVISIBLE (2275 250);
FORCEPROP 2 LAST CDS_SEC 1
J 0
(2275 250);
PAINT ORANGE (2275 250);
DISPLAY INVISIBLE (2275 250);
FORCEPROP 2 LAST SEC_TYPE 0603V
J 0
(2275 300);
DISPLAY 1.021277 (2275 300);
PAINT ORANGE (2275 300);
DISPLAY INVISIBLE (2275 300);
FORCEPROP 2 LAST SEC 1
J 0
(2275 300);
DISPLAY 0.680851 (2275 300);
PAINT MONO (2275 300);
DISPLAY INVISIBLE (2275 300);
FORCEPROP 2 LAST CDS_LIB dev_discrete
J 0
(2225 100);
PAINT ORANGE (2225 100);
DISPLAY INVISIBLE (2225 100);
FORCEPROP 2 LAST CDS_LOCATION C5A19
J 0
(2275 200);
DISPLAY 0.617021 (2275 200);
PAINT AQUA (2275 200);
DISPLAY INVISIBLE (2275 200);
FORCEADD CAP_A..1
(-2150 -650);
FORCEPROP 0 LAST GROUP PWR_MLCC_CAP
J 0
(-2094 -888);
DISPLAY 0.638298 (-2094 -888);
PAINT BROWN (-2094 -888);
DISPLAY BOTH (-2094 -888);
FORCEPROP 1 LAST VALUE 47UF
J 0
(-2100 -600);
DISPLAY 0.617021 (-2100 -600);
PAINT SKYBLUE (-2100 -600);
FORCEPROP 1 LAST LOCATION C5L6
J 0
(-2100 -550);
DISPLAY 0.617021 (-2100 -550);
PAINT AQUA (-2100 -550);
FORCEPROP 1 LAST TOLERANCE 20%
J 0
(-2100 -700);
DISPLAY 0.617021 (-2100 -700);
PAINT SKYBLUE (-2100 -700);
FORCEPROP 1 LAST MATERIAL X5R
J 0
(-2100 -750);
DISPLAY 0.617021 (-2100 -750);
PAINT SKYBLUE (-2100 -750);
FORCEPROP 1 LASTPIN (-2150 -750) $PN 2
J 0
(-2140 -770);
DISPLAY 0.617021 (-2140 -770);
PAINT ORANGE (-2140 -770);
FORCEPROP 1 LASTPIN (-2150 -550) $PN 1
J 0
(-2140 -570);
DISPLAY 0.617021 (-2140 -570);
PAINT ORANGE (-2140 -570);
FORCEPROP 1 LAST PACK_TYPE 0603V
J 0
(-2100 -850);
DISPLAY 0.617021 (-2100 -850);
PAINT SKYBLUE (-2100 -850);
FORCEPROP 1 LAST PART_NUMBER 602433-106
J 0
(-2100 -800);
DISPLAY 0.617021 (-2100 -800);
PAINT BLUE (-2100 -800);
FORCEPROP 1 LAST VOLTAGE 4V
J 0
(-2100 -650);
DISPLAY 0.617021 (-2100 -650);
PAINT SKYBLUE (-2100 -650);
FORCEPROP 0 LAST BOM_SS E15431-004
J 0
(-2111 -933);
DISPLAY 0.510638 (-2111 -933);
PAINT BROWN (-2111 -933);
DISPLAY BOTH (-2111 -933);
FORCEPROP 1 LAST PATH I278
J 0
(-2100 -500);
DISPLAY 0.978723 (-2100 -500);
PAINT WHITE (-2100 -500);
DISPLAY INVISIBLE (-2100 -500);
FORCEPROP 2 LAST CDS_LIB dev_discrete
J 0
(-2150 -650);
PAINT ORANGE (-2150 -650);
DISPLAY INVISIBLE (-2150 -650);
FORCEPROP 2 LAST SEC 1
J 0
(-2100 -450);
DISPLAY 0.680851 (-2100 -450);
PAINT MONO (-2100 -450);
DISPLAY INVISIBLE (-2100 -450);
FORCEPROP 2 LAST SEC_TYPE 0603V
J 0
(-2100 -450);
DISPLAY 1.021277 (-2100 -450);
PAINT ORANGE (-2100 -450);
DISPLAY INVISIBLE (-2100 -450);
FORCEPROP 2 LAST CDS_SEC 1
J 0
(-2100 -500);
PAINT ORANGE (-2100 -500);
DISPLAY INVISIBLE (-2100 -500);
FORCEPROP 2 LAST CDS_LOCATION C5L6
J 0
(-2100 -550);
DISPLAY 0.617021 (-2100 -550);
PAINT AQUA (-2100 -550);
DISPLAY INVISIBLE (-2100 -550);
FORCEADD CAP_A..1
(-1850 -650);
FORCEPROP 0 LAST GROUP PWR_MLCC_CAP
J 0
(-1794 -1063);
DISPLAY 0.638298 (-1794 -1063);
PAINT BROWN (-1794 -1063);
DISPLAY BOTH (-1794 -1063);
FORCEPROP 1 LAST LOCATION C5L7
J 0
(-1800 -550);
DISPLAY 0.617021 (-1800 -550);
PAINT AQUA (-1800 -550);
FORCEPROP 1 LAST TOLERANCE 20%
J 0
(-1800 -700);
DISPLAY 0.617021 (-1800 -700);
PAINT SKYBLUE (-1800 -700);
FORCEPROP 1 LAST PACK_TYPE 0603V
J 0
(-1800 -850);
DISPLAY 0.617021 (-1800 -850);
PAINT SKYBLUE (-1800 -850);
FORCEPROP 1 LAST MATERIAL X5R
J 0
(-1800 -750);
DISPLAY 0.617021 (-1800 -750);
PAINT SKYBLUE (-1800 -750);
FORCEPROP 1 LAST PART_NUMBER 602433-106
J 0
(-1800 -800);
DISPLAY 0.617021 (-1800 -800);
PAINT BLUE (-1800 -800);
FORCEPROP 1 LAST VOLTAGE 4V
J 0
(-1800 -650);
DISPLAY 0.617021 (-1800 -650);
PAINT SKYBLUE (-1800 -650);
FORCEPROP 1 LAST VALUE 47UF
J 0
(-1800 -600);
DISPLAY 0.617021 (-1800 -600);
PAINT SKYBLUE (-1800 -600);
FORCEPROP 1 LASTPIN (-1850 -550) $PN 1
J 0
(-1840 -570);
DISPLAY 0.617021 (-1840 -570);
PAINT ORANGE (-1840 -570);
FORCEPROP 1 LASTPIN (-1850 -750) $PN 2
J 0
(-1840 -770);
DISPLAY 0.617021 (-1840 -770);
PAINT ORANGE (-1840 -770);
FORCEPROP 0 LAST BOM_SS E15431-004
J 0
(-1846 -999);
DISPLAY 0.510638 (-1846 -999);
PAINT BROWN (-1846 -999);
DISPLAY BOTH (-1846 -999);
FORCEPROP 1 LAST PATH I279
J 0
(-1800 -500);
DISPLAY 0.978723 (-1800 -500);
PAINT WHITE (-1800 -500);
DISPLAY INVISIBLE (-1800 -500);
FORCEPROP 2 LAST CDS_SEC 1
J 0
(-1800 -500);
PAINT ORANGE (-1800 -500);
DISPLAY INVISIBLE (-1800 -500);
FORCEPROP 2 LAST SEC_TYPE 0603V
J 0
(-1800 -450);
DISPLAY 1.021277 (-1800 -450);
PAINT ORANGE (-1800 -450);
DISPLAY INVISIBLE (-1800 -450);
FORCEPROP 2 LAST SEC 1
J 0
(-1800 -450);
DISPLAY 0.680851 (-1800 -450);
PAINT MONO (-1800 -450);
DISPLAY INVISIBLE (-1800 -450);
FORCEPROP 2 LAST CDS_LIB dev_discrete
J 0
(-1850 -650);
PAINT ORANGE (-1850 -650);
DISPLAY INVISIBLE (-1850 -650);
FORCEPROP 2 LAST CDS_LOCATION C5L7
J 0
(-1800 -550);
DISPLAY 0.617021 (-1800 -550);
PAINT AQUA (-1800 -550);
DISPLAY INVISIBLE (-1800 -550);
FORCEADD CAP_A..1
(-1550 -650);
FORCEPROP 0 LAST GROUP PWR_MLCC_CAP
J 0
(-1494 -888);
DISPLAY 0.638298 (-1494 -888);
PAINT BROWN (-1494 -888);
DISPLAY BOTH (-1494 -888);
FORCEPROP 1 LAST PART_NUMBER 602433-106
J 0
(-1500 -800);
DISPLAY 0.617021 (-1500 -800);
PAINT BLUE (-1500 -800);
FORCEPROP 1 LAST PACK_TYPE 0603V
J 0
(-1500 -850);
DISPLAY 0.617021 (-1500 -850);
PAINT SKYBLUE (-1500 -850);
FORCEPROP 1 LAST TOLERANCE 20%
J 0
(-1500 -700);
DISPLAY 0.617021 (-1500 -700);
PAINT SKYBLUE (-1500 -700);
FORCEPROP 1 LAST MATERIAL X5R
J 0
(-1500 -750);
DISPLAY 0.617021 (-1500 -750);
PAINT SKYBLUE (-1500 -750);
FORCEPROP 1 LASTPIN (-1550 -750) $PN 2
J 0
(-1540 -770);
DISPLAY 0.617021 (-1540 -770);
PAINT ORANGE (-1540 -770);
FORCEPROP 1 LASTPIN (-1550 -550) $PN 1
J 0
(-1540 -570);
DISPLAY 0.617021 (-1540 -570);
PAINT ORANGE (-1540 -570);
FORCEPROP 1 LAST VOLTAGE 4V
J 0
(-1500 -650);
DISPLAY 0.617021 (-1500 -650);
PAINT SKYBLUE (-1500 -650);
FORCEPROP 1 LAST LOCATION C5L8
J 0
(-1500 -550);
DISPLAY 0.617021 (-1500 -550);
PAINT AQUA (-1500 -550);
FORCEPROP 1 LAST VALUE 47UF
J 0
(-1500 -600);
DISPLAY 0.617021 (-1500 -600);
PAINT SKYBLUE (-1500 -600);
FORCEPROP 0 LAST BOM_SS E15431-004
J 0
(-1531 -957);
DISPLAY 0.510638 (-1531 -957);
PAINT BROWN (-1531 -957);
DISPLAY BOTH (-1531 -957);
FORCEPROP 1 LAST PATH I280
J 0
(-1500 -500);
DISPLAY 0.978723 (-1500 -500);
PAINT WHITE (-1500 -500);
DISPLAY INVISIBLE (-1500 -500);
FORCEPROP 2 LAST CDS_LIB dev_discrete
J 0
(-1550 -650);
PAINT ORANGE (-1550 -650);
DISPLAY INVISIBLE (-1550 -650);
FORCEPROP 2 LAST SEC 1
J 0
(-1500 -450);
DISPLAY 0.680851 (-1500 -450);
PAINT MONO (-1500 -450);
DISPLAY INVISIBLE (-1500 -450);
FORCEPROP 2 LAST SEC_TYPE 0603V
J 0
(-1500 -450);
DISPLAY 1.021277 (-1500 -450);
PAINT ORANGE (-1500 -450);
DISPLAY INVISIBLE (-1500 -450);
FORCEPROP 2 LAST CDS_SEC 1
J 0
(-1500 -500);
PAINT ORANGE (-1500 -500);
DISPLAY INVISIBLE (-1500 -500);
FORCEPROP 2 LAST CDS_LOCATION C5L8
J 0
(-1500 -550);
DISPLAY 0.617021 (-1500 -550);
PAINT AQUA (-1500 -550);
DISPLAY INVISIBLE (-1500 -550);
FORCEADD CAP_A..1
(-1275 -650);
FORCEPROP 0 LAST GROUP PWR_MLCC_CAP
J 0
(-1219 -1063);
DISPLAY 0.638298 (-1219 -1063);
PAINT BROWN (-1219 -1063);
DISPLAY BOTH (-1219 -1063);
FORCEPROP 1 LAST LOCATION C5L9
J 0
(-1225 -550);
DISPLAY 0.617021 (-1225 -550);
PAINT AQUA (-1225 -550);
FORCEPROP 1 LASTPIN (-1275 -750) $PN 2
J 0
(-1265 -770);
DISPLAY 0.617021 (-1265 -770);
PAINT ORANGE (-1265 -770);
FORCEPROP 1 LAST MATERIAL X5R
J 0
(-1225 -750);
DISPLAY 0.617021 (-1225 -750);
PAINT SKYBLUE (-1225 -750);
FORCEPROP 1 LAST TOLERANCE 20%
J 0
(-1225 -700);
DISPLAY 0.617021 (-1225 -700);
PAINT SKYBLUE (-1225 -700);
FORCEPROP 1 LAST VOLTAGE 4V
J 0
(-1225 -650);
DISPLAY 0.617021 (-1225 -650);
PAINT SKYBLUE (-1225 -650);
FORCEPROP 1 LAST VALUE 47UF
J 0
(-1225 -600);
DISPLAY 0.617021 (-1225 -600);
PAINT SKYBLUE (-1225 -600);
FORCEPROP 1 LAST PACK_TYPE 0603V
J 0
(-1225 -850);
DISPLAY 0.617021 (-1225 -850);
PAINT SKYBLUE (-1225 -850);
FORCEPROP 1 LASTPIN (-1275 -550) $PN 1
J 0
(-1265 -570);
DISPLAY 0.617021 (-1265 -570);
PAINT ORANGE (-1265 -570);
FORCEPROP 1 LAST PART_NUMBER 602433-106
J 0
(-1225 -800);
DISPLAY 0.617021 (-1225 -800);
PAINT BLUE (-1225 -800);
FORCEPROP 0 LAST BOM_SS E15431-004
J 0
(-1241 -1008);
DISPLAY 0.510638 (-1241 -1008);
PAINT BROWN (-1241 -1008);
DISPLAY BOTH (-1241 -1008);
FORCEPROP 1 LAST PATH I281
J 0
(-1225 -500);
DISPLAY 0.978723 (-1225 -500);
PAINT WHITE (-1225 -500);
DISPLAY INVISIBLE (-1225 -500);
FORCEPROP 2 LAST CDS_SEC 1
J 0
(-1225 -500);
PAINT ORANGE (-1225 -500);
DISPLAY INVISIBLE (-1225 -500);
FORCEPROP 2 LAST SEC_TYPE 0603V
J 0
(-1225 -450);
DISPLAY 1.021277 (-1225 -450);
PAINT ORANGE (-1225 -450);
DISPLAY INVISIBLE (-1225 -450);
FORCEPROP 2 LAST SEC 1
J 0
(-1225 -450);
DISPLAY 0.680851 (-1225 -450);
PAINT MONO (-1225 -450);
DISPLAY INVISIBLE (-1225 -450);
FORCEPROP 2 LAST CDS_LIB dev_discrete
J 0
(-1275 -650);
PAINT ORANGE (-1275 -650);
DISPLAY INVISIBLE (-1275 -650);
FORCEPROP 2 LAST CDS_LOCATION C5L9
J 0
(-1225 -550);
DISPLAY 0.617021 (-1225 -550);
PAINT AQUA (-1225 -550);
DISPLAY INVISIBLE (-1225 -550);
FORCEADD CAP_A..1
(-1000 -650);
FORCEPROP 0 LAST GROUP PWR_MLCC_CAP
J 0
(-944 -888);
DISPLAY 0.638298 (-944 -888);
PAINT BROWN (-944 -888);
DISPLAY BOTH (-944 -888);
FORCEPROP 1 LAST MATERIAL X5R
J 0
(-950 -750);
DISPLAY 0.617021 (-950 -750);
PAINT SKYBLUE (-950 -750);
FORCEPROP 1 LAST PART_NUMBER 602433-106
J 0
(-950 -800);
DISPLAY 0.617021 (-950 -800);
PAINT BLUE (-950 -800);
FORCEPROP 1 LAST PACK_TYPE 0603V
J 0
(-950 -850);
DISPLAY 0.617021 (-950 -850);
PAINT SKYBLUE (-950 -850);
FORCEPROP 1 LASTPIN (-1000 -750) $PN 2
J 0
(-990 -770);
DISPLAY 0.617021 (-990 -770);
PAINT ORANGE (-990 -770);
FORCEPROP 1 LAST LOCATION C5L10
J 0
(-950 -550);
DISPLAY 0.617021 (-950 -550);
PAINT AQUA (-950 -550);
FORCEPROP 1 LAST TOLERANCE 20%
J 0
(-950 -700);
DISPLAY 0.617021 (-950 -700);
PAINT SKYBLUE (-950 -700);
FORCEPROP 1 LASTPIN (-1000 -550) $PN 1
J 0
(-990 -570);
DISPLAY 0.617021 (-990 -570);
PAINT ORANGE (-990 -570);
FORCEPROP 1 LAST VALUE 47UF
J 0
(-950 -600);
DISPLAY 0.617021 (-950 -600);
PAINT SKYBLUE (-950 -600);
FORCEPROP 1 LAST VOLTAGE 4V
J 0
(-950 -650);
DISPLAY 0.617021 (-950 -650);
PAINT SKYBLUE (-950 -650);
FORCEPROP 0 LAST BOM_SS E15431-004
J 0
(-998 -945);
DISPLAY 0.510638 (-998 -945);
PAINT BROWN (-998 -945);
DISPLAY BOTH (-998 -945);
FORCEPROP 1 LAST PATH I282
J 0
(-950 -500);
DISPLAY 0.978723 (-950 -500);
PAINT WHITE (-950 -500);
DISPLAY INVISIBLE (-950 -500);
FORCEPROP 2 LAST CDS_LIB dev_discrete
J 0
(-1000 -650);
PAINT ORANGE (-1000 -650);
DISPLAY INVISIBLE (-1000 -650);
FORCEPROP 2 LAST SEC 1
J 0
(-950 -450);
DISPLAY 0.680851 (-950 -450);
PAINT MONO (-950 -450);
DISPLAY INVISIBLE (-950 -450);
FORCEPROP 2 LAST SEC_TYPE 0603V
J 0
(-950 -450);
DISPLAY 1.021277 (-950 -450);
PAINT ORANGE (-950 -450);
DISPLAY INVISIBLE (-950 -450);
FORCEPROP 2 LAST CDS_SEC 1
J 0
(-950 -500);
PAINT ORANGE (-950 -500);
DISPLAY INVISIBLE (-950 -500);
FORCEPROP 2 LAST CDS_LOCATION C5L10
J 0
(-950 -550);
DISPLAY 0.617021 (-950 -550);
PAINT AQUA (-950 -550);
DISPLAY INVISIBLE (-950 -550);
FORCEADD CAP_A..1
(-700 -650);
FORCEPROP 0 LAST GROUP PWR_MLCC_CAP
J 0
(-644 -1063);
DISPLAY 0.638298 (-644 -1063);
PAINT BROWN (-644 -1063);
DISPLAY BOTH (-644 -1063);
FORCEPROP 1 LAST VALUE 47UF
J 0
(-650 -600);
DISPLAY 0.617021 (-650 -600);
PAINT SKYBLUE (-650 -600);
FORCEPROP 1 LAST PART_NUMBER 602433-106
J 0
(-650 -800);
DISPLAY 0.617021 (-650 -800);
PAINT BLUE (-650 -800);
FORCEPROP 1 LAST PACK_TYPE 0603V
J 0
(-650 -850);
DISPLAY 0.617021 (-650 -850);
PAINT SKYBLUE (-650 -850);
FORCEPROP 1 LAST LOCATION C5L11
J 0
(-650 -550);
DISPLAY 0.617021 (-650 -550);
PAINT AQUA (-650 -550);
FORCEPROP 1 LASTPIN (-700 -550) $PN 1
J 0
(-690 -570);
DISPLAY 0.617021 (-690 -570);
PAINT ORANGE (-690 -570);
FORCEPROP 1 LAST VOLTAGE 4V
J 0
(-650 -650);
DISPLAY 0.617021 (-650 -650);
PAINT SKYBLUE (-650 -650);
FORCEPROP 1 LASTPIN (-700 -750) $PN 2
J 0
(-690 -770);
DISPLAY 0.617021 (-690 -770);
PAINT ORANGE (-690 -770);
FORCEPROP 1 LAST MATERIAL X5R
J 0
(-650 -750);
DISPLAY 0.617021 (-650 -750);
PAINT SKYBLUE (-650 -750);
FORCEPROP 1 LAST TOLERANCE 20%
J 0
(-650 -700);
DISPLAY 0.617021 (-650 -700);
PAINT SKYBLUE (-650 -700);
FORCEPROP 0 LAST BOM_SS E15431-004
J 0
(-657 -1002);
DISPLAY 0.510638 (-657 -1002);
PAINT BROWN (-657 -1002);
DISPLAY BOTH (-657 -1002);
FORCEPROP 1 LAST PATH I283
J 0
(-650 -500);
DISPLAY 0.978723 (-650 -500);
PAINT WHITE (-650 -500);
DISPLAY INVISIBLE (-650 -500);
FORCEPROP 2 LAST CDS_SEC 1
J 0
(-650 -500);
PAINT ORANGE (-650 -500);
DISPLAY INVISIBLE (-650 -500);
FORCEPROP 2 LAST SEC_TYPE 0603V
J 0
(-650 -450);
DISPLAY 1.021277 (-650 -450);
PAINT ORANGE (-650 -450);
DISPLAY INVISIBLE (-650 -450);
FORCEPROP 2 LAST SEC 1
J 0
(-650 -450);
DISPLAY 0.680851 (-650 -450);
PAINT MONO (-650 -450);
DISPLAY INVISIBLE (-650 -450);
FORCEPROP 2 LAST CDS_LIB dev_discrete
J 0
(-700 -650);
PAINT ORANGE (-700 -650);
DISPLAY INVISIBLE (-700 -650);
FORCEPROP 2 LAST CDS_LOCATION C5L11
J 0
(-650 -550);
DISPLAY 0.617021 (-650 -550);
PAINT AQUA (-650 -550);
DISPLAY INVISIBLE (-650 -550);
FORCEADD CAP_A..1
(-400 -650);
FORCEPROP 0 LAST GROUP PWR_MLCC_CAP
J 0
(-344 -888);
DISPLAY 0.638298 (-344 -888);
PAINT BROWN (-344 -888);
DISPLAY BOTH (-344 -888);
FORCEPROP 1 LAST TOLERANCE 20%
J 0
(-350 -700);
DISPLAY 0.617021 (-350 -700);
PAINT SKYBLUE (-350 -700);
FORCEPROP 1 LAST LOCATION C5L12
J 0
(-350 -550);
DISPLAY 0.617021 (-350 -550);
PAINT AQUA (-350 -550);
FORCEPROP 1 LAST VALUE 47UF
J 0
(-350 -600);
DISPLAY 0.617021 (-350 -600);
PAINT SKYBLUE (-350 -600);
FORCEPROP 1 LAST PACK_TYPE 0603V
J 0
(-350 -850);
DISPLAY 0.617021 (-350 -850);
PAINT SKYBLUE (-350 -850);
FORCEPROP 1 LASTPIN (-400 -750) $PN 2
J 0
(-390 -770);
DISPLAY 0.617021 (-390 -770);
PAINT ORANGE (-390 -770);
FORCEPROP 1 LASTPIN (-400 -550) $PN 1
J 0
(-390 -570);
DISPLAY 0.617021 (-390 -570);
PAINT ORANGE (-390 -570);
FORCEPROP 1 LAST PART_NUMBER 602433-106
J 0
(-350 -800);
DISPLAY 0.617021 (-350 -800);
PAINT BLUE (-350 -800);
FORCEPROP 1 LAST VOLTAGE 4V
J 0
(-350 -650);
DISPLAY 0.617021 (-350 -650);
PAINT SKYBLUE (-350 -650);
FORCEPROP 1 LAST MATERIAL X5R
J 0
(-350 -750);
DISPLAY 0.617021 (-350 -750);
PAINT SKYBLUE (-350 -750);
FORCEPROP 0 LAST BOM_SS E15431-004
J 0
(-375 -947);
DISPLAY 0.510638 (-375 -947);
PAINT BROWN (-375 -947);
DISPLAY BOTH (-375 -947);
FORCEPROP 1 LAST PATH I284
J 0
(-350 -500);
DISPLAY 0.978723 (-350 -500);
PAINT WHITE (-350 -500);
DISPLAY INVISIBLE (-350 -500);
FORCEPROP 2 LAST CDS_LIB dev_discrete
J 0
(-400 -650);
PAINT ORANGE (-400 -650);
DISPLAY INVISIBLE (-400 -650);
FORCEPROP 2 LAST SEC 1
J 0
(-350 -450);
DISPLAY 0.680851 (-350 -450);
PAINT MONO (-350 -450);
DISPLAY INVISIBLE (-350 -450);
FORCEPROP 2 LAST SEC_TYPE 0603V
J 0
(-350 -450);
DISPLAY 1.021277 (-350 -450);
PAINT ORANGE (-350 -450);
DISPLAY INVISIBLE (-350 -450);
FORCEPROP 2 LAST CDS_SEC 1
J 0
(-350 -500);
PAINT ORANGE (-350 -500);
DISPLAY INVISIBLE (-350 -500);
FORCEPROP 2 LAST CDS_LOCATION C5L12
J 0
(-350 -550);
DISPLAY 0.617021 (-350 -550);
PAINT AQUA (-350 -550);
DISPLAY INVISIBLE (-350 -550);
FORCEADD CAP_A..1
(-125 -650);
FORCEPROP 0 LAST GROUP PWR_MLCC_CAP
J 0
(-69 -1063);
DISPLAY 0.638298 (-69 -1063);
PAINT BROWN (-69 -1063);
DISPLAY BOTH (-69 -1063);
FORCEPROP 1 LAST MATERIAL X5R
J 0
(-75 -750);
DISPLAY 0.617021 (-75 -750);
PAINT SKYBLUE (-75 -750);
FORCEPROP 1 LAST PART_NUMBER 602433-106
J 0
(-75 -800);
DISPLAY 0.617021 (-75 -800);
PAINT BLUE (-75 -800);
FORCEPROP 1 LAST LOCATION C5L13
J 0
(-75 -550);
DISPLAY 0.617021 (-75 -550);
PAINT AQUA (-75 -550);
FORCEPROP 1 LAST VALUE 47UF
J 0
(-75 -600);
DISPLAY 0.617021 (-75 -600);
PAINT SKYBLUE (-75 -600);
FORCEPROP 1 LAST TOLERANCE 20%
J 0
(-75 -700);
DISPLAY 0.617021 (-75 -700);
PAINT SKYBLUE (-75 -700);
FORCEPROP 1 LAST VOLTAGE 4V
J 0
(-75 -650);
DISPLAY 0.617021 (-75 -650);
PAINT SKYBLUE (-75 -650);
FORCEPROP 1 LAST PACK_TYPE 0603V
J 0
(-75 -850);
DISPLAY 0.617021 (-75 -850);
PAINT SKYBLUE (-75 -850);
FORCEPROP 1 LASTPIN (-125 -550) $PN 1
J 0
(-115 -570);
DISPLAY 0.617021 (-115 -570);
PAINT ORANGE (-115 -570);
FORCEPROP 1 LASTPIN (-125 -750) $PN 2
J 0
(-115 -770);
DISPLAY 0.617021 (-115 -770);
PAINT ORANGE (-115 -770);
FORCEPROP 0 LAST BOM_SS E15431-004
J 0
(-110 -990);
DISPLAY 0.510638 (-110 -990);
PAINT BROWN (-110 -990);
DISPLAY BOTH (-110 -990);
FORCEPROP 1 LAST PATH I285
J 0
(-75 -500);
DISPLAY 0.978723 (-75 -500);
PAINT WHITE (-75 -500);
DISPLAY INVISIBLE (-75 -500);
FORCEPROP 2 LAST CDS_SEC 1
J 0
(-75 -500);
PAINT ORANGE (-75 -500);
DISPLAY INVISIBLE (-75 -500);
FORCEPROP 2 LAST SEC_TYPE 0603V
J 0
(-75 -450);
DISPLAY 1.021277 (-75 -450);
PAINT ORANGE (-75 -450);
DISPLAY INVISIBLE (-75 -450);
FORCEPROP 2 LAST SEC 1
J 0
(-75 -450);
DISPLAY 0.680851 (-75 -450);
PAINT MONO (-75 -450);
DISPLAY INVISIBLE (-75 -450);
FORCEPROP 2 LAST CDS_LIB dev_discrete
J 0
(-125 -650);
PAINT ORANGE (-125 -650);
DISPLAY INVISIBLE (-125 -650);
FORCEPROP 2 LAST CDS_LOCATION C5L13
J 0
(-75 -550);
DISPLAY 0.617021 (-75 -550);
PAINT AQUA (-75 -550);
DISPLAY INVISIBLE (-75 -550);
FORCEADD CAP_A..1
(200 -650);
FORCEPROP 1 LAST PART_NUMBER 602433-106
J 0
(250 -800);
DISPLAY 0.617021 (250 -800);
PAINT BLUE (250 -800);
FORCEPROP 0 LAST GROUP PWR_MLCC_CAP
J 0
(256 -888);
DISPLAY 0.638298 (256 -888);
PAINT BROWN (256 -888);
DISPLAY BOTH (256 -888);
FORCEPROP 1 LASTPIN (200 -750) $PN 2
J 0
(210 -770);
DISPLAY 0.617021 (210 -770);
PAINT ORANGE (210 -770);
FORCEPROP 1 LAST MATERIAL X5R
J 0
(250 -750);
DISPLAY 0.617021 (250 -750);
PAINT SKYBLUE (250 -750);
FORCEPROP 1 LAST TOLERANCE 20%
J 0
(250 -700);
DISPLAY 0.617021 (250 -700);
PAINT SKYBLUE (250 -700);
FORCEPROP 1 LASTPIN (200 -550) $PN 1
J 0
(210 -570);
DISPLAY 0.617021 (210 -570);
PAINT ORANGE (210 -570);
FORCEPROP 1 LAST PACK_TYPE 0603V
J 0
(250 -850);
DISPLAY 0.617021 (250 -850);
PAINT SKYBLUE (250 -850);
FORCEPROP 1 LAST VALUE 47UF
J 0
(250 -600);
DISPLAY 0.617021 (250 -600);
PAINT SKYBLUE (250 -600);
FORCEPROP 1 LAST LOCATION C5M7
J 0
(250 -550);
DISPLAY 0.617021 (250 -550);
PAINT AQUA (250 -550);
FORCEPROP 1 LAST VOLTAGE 4V
J 0
(250 -650);
DISPLAY 0.617021 (250 -650);
PAINT SKYBLUE (250 -650);
FORCEPROP 0 LAST BOM_SS E15431-004
J 0
(226 -932);
DISPLAY 0.510638 (226 -932);
PAINT BROWN (226 -932);
DISPLAY BOTH (226 -932);
FORCEPROP 1 LAST PATH I286
J 0
(250 -500);
DISPLAY 0.978723 (250 -500);
PAINT WHITE (250 -500);
DISPLAY INVISIBLE (250 -500);
FORCEPROP 2 LAST CDS_LIB dev_discrete
J 0
(200 -650);
PAINT ORANGE (200 -650);
DISPLAY INVISIBLE (200 -650);
FORCEPROP 2 LAST SEC 1
J 0
(250 -450);
DISPLAY 0.680851 (250 -450);
PAINT MONO (250 -450);
DISPLAY INVISIBLE (250 -450);
FORCEPROP 2 LAST SEC_TYPE 0603V
J 0
(250 -450);
DISPLAY 1.021277 (250 -450);
PAINT ORANGE (250 -450);
DISPLAY INVISIBLE (250 -450);
FORCEPROP 2 LAST CDS_SEC 1
J 0
(250 -500);
PAINT ORANGE (250 -500);
DISPLAY INVISIBLE (250 -500);
FORCEPROP 2 LAST CDS_LOCATION C5M7
J 0
(250 -550);
DISPLAY 0.617021 (250 -550);
PAINT AQUA (250 -550);
DISPLAY INVISIBLE (250 -550);
FORCEADD CAP_A..1
(500 -650);
FORCEPROP 0 LAST GROUP PWR_MLCC_CAP
J 0
(556 -1063);
DISPLAY 0.638298 (556 -1063);
PAINT BROWN (556 -1063);
DISPLAY BOTH (556 -1063);
FORCEPROP 1 LAST TOLERANCE 20%
J 0
(550 -700);
DISPLAY 0.617021 (550 -700);
PAINT SKYBLUE (550 -700);
FORCEPROP 1 LAST MATERIAL X5R
J 0
(550 -750);
DISPLAY 0.617021 (550 -750);
PAINT SKYBLUE (550 -750);
FORCEPROP 1 LASTPIN (500 -750) $PN 2
J 0
(510 -770);
DISPLAY 0.617021 (510 -770);
PAINT ORANGE (510 -770);
FORCEPROP 1 LAST PART_NUMBER 602433-106
J 0
(550 -800);
DISPLAY 0.617021 (550 -800);
PAINT BLUE (550 -800);
FORCEPROP 1 LAST LOCATION C5M6
J 0
(550 -550);
DISPLAY 0.617021 (550 -550);
PAINT AQUA (550 -550);
FORCEPROP 1 LAST VOLTAGE 4V
J 0
(550 -650);
DISPLAY 0.617021 (550 -650);
PAINT SKYBLUE (550 -650);
FORCEPROP 1 LAST VALUE 47UF
J 0
(550 -600);
DISPLAY 0.617021 (550 -600);
PAINT SKYBLUE (550 -600);
FORCEPROP 1 LASTPIN (500 -550) $PN 1
J 0
(510 -570);
DISPLAY 0.617021 (510 -570);
PAINT ORANGE (510 -570);
FORCEPROP 1 LAST PACK_TYPE 0603V
J 0
(550 -850);
DISPLAY 0.617021 (550 -850);
PAINT SKYBLUE (550 -850);
FORCEPROP 0 LAST BOM_SS E15431-004
J 0
(525 -983);
DISPLAY 0.510638 (525 -983);
PAINT BROWN (525 -983);
DISPLAY BOTH (525 -983);
FORCEPROP 1 LAST PATH I287
J 0
(550 -500);
DISPLAY 0.978723 (550 -500);
PAINT WHITE (550 -500);
DISPLAY INVISIBLE (550 -500);
FORCEPROP 2 LAST CDS_SEC 1
J 0
(550 -500);
PAINT ORANGE (550 -500);
DISPLAY INVISIBLE (550 -500);
FORCEPROP 2 LAST SEC_TYPE 0603V
J 0
(550 -450);
DISPLAY 1.021277 (550 -450);
PAINT ORANGE (550 -450);
DISPLAY INVISIBLE (550 -450);
FORCEPROP 2 LAST SEC 1
J 0
(550 -450);
DISPLAY 0.680851 (550 -450);
PAINT MONO (550 -450);
DISPLAY INVISIBLE (550 -450);
FORCEPROP 2 LAST CDS_LIB dev_discrete
J 0
(500 -650);
PAINT ORANGE (500 -650);
DISPLAY INVISIBLE (500 -650);
FORCEPROP 2 LAST CDS_LOCATION C5M6
J 0
(550 -550);
DISPLAY 0.617021 (550 -550);
PAINT AQUA (550 -550);
DISPLAY INVISIBLE (550 -550);
FORCEADD CAP_A..1
(800 -650);
FORCEPROP 0 LAST GROUP PWR_MLCC_CAP
J 0
(856 -888);
DISPLAY 0.638298 (856 -888);
PAINT BROWN (856 -888);
DISPLAY BOTH (856 -888);
FORCEPROP 1 LAST LOCATION C5M5
J 0
(850 -550);
DISPLAY 0.617021 (850 -550);
PAINT AQUA (850 -550);
FORCEPROP 1 LAST VALUE 47UF
J 0
(850 -600);
DISPLAY 0.617021 (850 -600);
PAINT SKYBLUE (850 -600);
FORCEPROP 1 LAST TOLERANCE 20%
J 0
(850 -700);
DISPLAY 0.617021 (850 -700);
PAINT SKYBLUE (850 -700);
FORCEPROP 1 LAST PART_NUMBER 602433-106
J 0
(850 -800);
DISPLAY 0.617021 (850 -800);
PAINT BLUE (850 -800);
FORCEPROP 1 LAST MATERIAL X5R
J 0
(850 -750);
DISPLAY 0.617021 (850 -750);
PAINT SKYBLUE (850 -750);
FORCEPROP 1 LASTPIN (800 -550) $PN 1
J 0
(810 -570);
DISPLAY 0.617021 (810 -570);
PAINT ORANGE (810 -570);
FORCEPROP 1 LAST VOLTAGE 4V
J 0
(850 -650);
DISPLAY 0.617021 (850 -650);
PAINT SKYBLUE (850 -650);
FORCEPROP 1 LASTPIN (800 -750) $PN 2
J 0
(810 -770);
DISPLAY 0.617021 (810 -770);
PAINT ORANGE (810 -770);
FORCEPROP 1 LAST PACK_TYPE 0603V
J 0
(850 -850);
DISPLAY 0.617021 (850 -850);
PAINT SKYBLUE (850 -850);
FORCEPROP 0 LAST BOM_SS E15431-004
J 0
(811 -957);
DISPLAY 0.510638 (811 -957);
PAINT BROWN (811 -957);
DISPLAY BOTH (811 -957);
FORCEPROP 1 LAST PATH I288
J 0
(850 -500);
DISPLAY 0.978723 (850 -500);
PAINT WHITE (850 -500);
DISPLAY INVISIBLE (850 -500);
FORCEPROP 2 LAST CDS_LIB dev_discrete
J 0
(800 -650);
PAINT ORANGE (800 -650);
DISPLAY INVISIBLE (800 -650);
FORCEPROP 2 LAST SEC 1
J 0
(850 -450);
DISPLAY 0.680851 (850 -450);
PAINT MONO (850 -450);
DISPLAY INVISIBLE (850 -450);
FORCEPROP 2 LAST SEC_TYPE 0603V
J 0
(850 -450);
DISPLAY 1.021277 (850 -450);
PAINT ORANGE (850 -450);
DISPLAY INVISIBLE (850 -450);
FORCEPROP 2 LAST CDS_SEC 1
J 0
(850 -500);
PAINT ORANGE (850 -500);
DISPLAY INVISIBLE (850 -500);
FORCEPROP 2 LAST CDS_LOCATION C5M5
J 0
(850 -550);
DISPLAY 0.617021 (850 -550);
PAINT AQUA (850 -550);
DISPLAY INVISIBLE (850 -550);
FORCEADD CAP_A..1
(1075 -650);
FORCEPROP 0 LAST GROUP PWR_MLCC_CAP
J 0
(1156 -1063);
DISPLAY 0.638298 (1156 -1063);
PAINT BROWN (1156 -1063);
DISPLAY BOTH (1156 -1063);
FORCEPROP 1 LAST PART_NUMBER 602433-106
J 0
(1125 -800);
DISPLAY 0.617021 (1125 -800);
PAINT BLUE (1125 -800);
FORCEPROP 1 LAST TOLERANCE 20%
J 0
(1125 -700);
DISPLAY 0.617021 (1125 -700);
PAINT SKYBLUE (1125 -700);
FORCEPROP 1 LAST PACK_TYPE 0603V
J 0
(1125 -850);
DISPLAY 0.617021 (1125 -850);
PAINT SKYBLUE (1125 -850);
FORCEPROP 1 LAST LOCATION C5M4
J 0
(1125 -550);
DISPLAY 0.617021 (1125 -550);
PAINT AQUA (1125 -550);
FORCEPROP 1 LAST VOLTAGE 4V
J 0
(1125 -650);
DISPLAY 0.617021 (1125 -650);
PAINT SKYBLUE (1125 -650);
FORCEPROP 1 LAST VALUE 47UF
J 0
(1125 -600);
DISPLAY 0.617021 (1125 -600);
PAINT SKYBLUE (1125 -600);
FORCEPROP 1 LASTPIN (1075 -750) $PN 2
J 0
(1085 -770);
DISPLAY 0.617021 (1085 -770);
PAINT ORANGE (1085 -770);
FORCEPROP 1 LAST MATERIAL X5R
J 0
(1125 -750);
DISPLAY 0.617021 (1125 -750);
PAINT SKYBLUE (1125 -750);
FORCEPROP 0 LAST BOM_SS E15431-004
J 0
(1075 -1003);
DISPLAY 0.510638 (1075 -1003);
PAINT BROWN (1075 -1003);
DISPLAY BOTH (1075 -1003);
FORCEPROP 1 LASTPIN (1075 -550) $PN 1
J 0
(1085 -570);
DISPLAY 0.617021 (1085 -570);
PAINT ORANGE (1085 -570);
FORCEPROP 1 LAST PATH I289
J 0
(1125 -500);
DISPLAY 0.978723 (1125 -500);
PAINT WHITE (1125 -500);
DISPLAY INVISIBLE (1125 -500);
FORCEPROP 2 LAST CDS_SEC 1
J 0
(1125 -500);
PAINT ORANGE (1125 -500);
DISPLAY INVISIBLE (1125 -500);
FORCEPROP 2 LAST SEC_TYPE 0603V
J 0
(1125 -450);
DISPLAY 1.021277 (1125 -450);
PAINT ORANGE (1125 -450);
DISPLAY INVISIBLE (1125 -450);
FORCEPROP 2 LAST SEC 1
J 0
(1125 -450);
DISPLAY 0.680851 (1125 -450);
PAINT MONO (1125 -450);
DISPLAY INVISIBLE (1125 -450);
FORCEPROP 2 LAST CDS_LIB dev_discrete
J 0
(1075 -650);
PAINT ORANGE (1075 -650);
DISPLAY INVISIBLE (1075 -650);
FORCEPROP 2 LAST CDS_LOCATION C5M4
J 0
(1125 -550);
DISPLAY 0.617021 (1125 -550);
PAINT AQUA (1125 -550);
DISPLAY INVISIBLE (1125 -550);
FORCEADD CAP_A..1
(1350 -650);
FORCEPROP 0 LAST GROUP PWR_MLCC_CAP
J 0
(1406 -888);
DISPLAY 0.638298 (1406 -888);
PAINT BROWN (1406 -888);
DISPLAY BOTH (1406 -888);
FORCEPROP 1 LAST PART_NUMBER 602433-106
J 0
(1400 -800);
DISPLAY 0.617021 (1400 -800);
PAINT BLUE (1400 -800);
FORCEPROP 1 LAST PACK_TYPE 0603V
J 0
(1400 -850);
DISPLAY 0.617021 (1400 -850);
PAINT SKYBLUE (1400 -850);
FORCEPROP 1 LAST TOLERANCE 20%
J 0
(1400 -700);
DISPLAY 0.617021 (1400 -700);
PAINT SKYBLUE (1400 -700);
FORCEPROP 1 LAST MATERIAL X5R
J 0
(1400 -750);
DISPLAY 0.617021 (1400 -750);
PAINT SKYBLUE (1400 -750);
FORCEPROP 1 LASTPIN (1350 -750) $PN 2
J 0
(1360 -770);
DISPLAY 0.617021 (1360 -770);
PAINT ORANGE (1360 -770);
FORCEPROP 1 LASTPIN (1350 -550) $PN 1
J 0
(1360 -570);
DISPLAY 0.617021 (1360 -570);
PAINT ORANGE (1360 -570);
FORCEPROP 1 LAST VALUE 47UF
J 0
(1400 -600);
DISPLAY 0.617021 (1400 -600);
PAINT SKYBLUE (1400 -600);
FORCEPROP 1 LAST VOLTAGE 4V
J 0
(1400 -650);
DISPLAY 0.617021 (1400 -650);
PAINT SKYBLUE (1400 -650);
FORCEPROP 1 LAST LOCATION C5M2
J 0
(1400 -550);
DISPLAY 0.617021 (1400 -550);
PAINT AQUA (1400 -550);
FORCEPROP 0 LAST BOM_SS E15431-004
J 0
(1369 -950);
DISPLAY 0.510638 (1369 -950);
PAINT BROWN (1369 -950);
DISPLAY BOTH (1369 -950);
FORCEPROP 1 LAST PATH I290
J 0
(1400 -500);
DISPLAY 0.978723 (1400 -500);
PAINT WHITE (1400 -500);
DISPLAY INVISIBLE (1400 -500);
FORCEPROP 2 LAST CDS_LIB dev_discrete
J 0
(1350 -650);
PAINT ORANGE (1350 -650);
DISPLAY INVISIBLE (1350 -650);
FORCEPROP 2 LAST SEC 1
J 0
(1400 -450);
DISPLAY 0.680851 (1400 -450);
PAINT MONO (1400 -450);
DISPLAY INVISIBLE (1400 -450);
FORCEPROP 2 LAST SEC_TYPE 0603V
J 0
(1400 -450);
DISPLAY 1.021277 (1400 -450);
PAINT ORANGE (1400 -450);
DISPLAY INVISIBLE (1400 -450);
FORCEPROP 2 LAST CDS_SEC 1
J 0
(1400 -500);
PAINT ORANGE (1400 -500);
DISPLAY INVISIBLE (1400 -500);
FORCEPROP 2 LAST CDS_LOCATION C5M2
J 0
(1400 -550);
DISPLAY 0.617021 (1400 -550);
PAINT AQUA (1400 -550);
DISPLAY INVISIBLE (1400 -550);
FORCEADD CAP_A..1
(1650 -650);
FORCEPROP 1 LAST PACK_TYPE 0603V
J 0
(1700 -850);
DISPLAY 0.617021 (1700 -850);
PAINT SKYBLUE (1700 -850);
FORCEPROP 0 LAST GROUP PWR_MLCC_CAP
J 0
(1706 -1063);
DISPLAY 0.638298 (1706 -1063);
PAINT BROWN (1706 -1063);
DISPLAY BOTH (1706 -1063);
FORCEPROP 1 LASTPIN (1650 -750) $PN 2
J 0
(1660 -770);
DISPLAY 0.617021 (1660 -770);
PAINT ORANGE (1660 -770);
FORCEPROP 1 LAST MATERIAL X5R
J 0
(1700 -750);
DISPLAY 0.617021 (1700 -750);
PAINT SKYBLUE (1700 -750);
FORCEPROP 1 LAST LOCATION C5M1
J 0
(1700 -550);
DISPLAY 0.617021 (1700 -550);
PAINT AQUA (1700 -550);
FORCEPROP 1 LAST VOLTAGE 4V
J 0
(1700 -650);
DISPLAY 0.617021 (1700 -650);
PAINT SKYBLUE (1700 -650);
FORCEPROP 1 LASTPIN (1650 -550) $PN 1
J 0
(1660 -570);
DISPLAY 0.617021 (1660 -570);
PAINT ORANGE (1660 -570);
FORCEPROP 1 LAST TOLERANCE 20%
J 0
(1700 -700);
DISPLAY 0.617021 (1700 -700);
PAINT SKYBLUE (1700 -700);
FORCEPROP 1 LAST VALUE 47UF
J 0
(1700 -600);
DISPLAY 0.617021 (1700 -600);
PAINT SKYBLUE (1700 -600);
FORCEPROP 1 LAST PART_NUMBER 602433-106
J 0
(1700 -800);
DISPLAY 0.617021 (1700 -800);
PAINT BLUE (1700 -800);
FORCEPROP 0 LAST BOM_SS E15431-004
J 0
(1657 -985);
DISPLAY 0.510638 (1657 -985);
PAINT BROWN (1657 -985);
DISPLAY BOTH (1657 -985);
FORCEPROP 1 LAST PATH I291
J 0
(1700 -500);
DISPLAY 0.978723 (1700 -500);
PAINT WHITE (1700 -500);
DISPLAY INVISIBLE (1700 -500);
FORCEPROP 2 LAST CDS_SEC 1
J 0
(1700 -500);
PAINT ORANGE (1700 -500);
DISPLAY INVISIBLE (1700 -500);
FORCEPROP 2 LAST SEC_TYPE 0603V
J 0
(1700 -450);
DISPLAY 1.021277 (1700 -450);
PAINT ORANGE (1700 -450);
DISPLAY INVISIBLE (1700 -450);
FORCEPROP 2 LAST SEC 1
J 0
(1700 -450);
DISPLAY 0.680851 (1700 -450);
PAINT MONO (1700 -450);
DISPLAY INVISIBLE (1700 -450);
FORCEPROP 2 LAST CDS_LIB dev_discrete
J 0
(1650 -650);
PAINT ORANGE (1650 -650);
DISPLAY INVISIBLE (1650 -650);
FORCEPROP 2 LAST CDS_LOCATION C5M1
J 0
(1700 -550);
DISPLAY 0.617021 (1700 -550);
PAINT AQUA (1700 -550);
DISPLAY INVISIBLE (1700 -550);
FORCEADD CAP_A..1
(1950 -650);
FORCEPROP 1 LAST PART_NUMBER 602433-106
J 0
(2000 -800);
DISPLAY 0.617021 (2000 -800);
PAINT BLUE (2000 -800);
FORCEPROP 0 LAST GROUP PWR_MLCC_CAP
J 0
(2006 -888);
DISPLAY 0.638298 (2006 -888);
PAINT BROWN (2006 -888);
DISPLAY BOTH (2006 -888);
FORCEPROP 1 LAST TOLERANCE 20%
J 0
(2000 -700);
DISPLAY 0.617021 (2000 -700);
PAINT SKYBLUE (2000 -700);
FORCEPROP 1 LAST LOCATION C4M2
J 0
(2000 -550);
DISPLAY 0.617021 (2000 -550);
PAINT AQUA (2000 -550);
FORCEPROP 1 LAST VALUE 47UF
J 0
(2000 -600);
DISPLAY 0.617021 (2000 -600);
PAINT SKYBLUE (2000 -600);
FORCEPROP 1 LASTPIN (1950 -750) $PN 2
J 0
(1960 -770);
DISPLAY 0.617021 (1960 -770);
PAINT ORANGE (1960 -770);
FORCEPROP 1 LAST PACK_TYPE 0603V
J 0
(2000 -850);
DISPLAY 0.617021 (2000 -850);
PAINT SKYBLUE (2000 -850);
FORCEPROP 1 LASTPIN (1950 -550) $PN 1
J 0
(1960 -570);
DISPLAY 0.617021 (1960 -570);
PAINT ORANGE (1960 -570);
FORCEPROP 1 LAST MATERIAL X5R
J 0
(2000 -750);
DISPLAY 0.617021 (2000 -750);
PAINT SKYBLUE (2000 -750);
FORCEPROP 1 LAST VOLTAGE 4V
J 0
(2000 -650);
DISPLAY 0.617021 (2000 -650);
PAINT SKYBLUE (2000 -650);
FORCEPROP 0 LAST BOM_SS E15431-004
J 0
(1987 -959);
DISPLAY 0.510638 (1987 -959);
PAINT BROWN (1987 -959);
DISPLAY BOTH (1987 -959);
FORCEPROP 1 LAST PATH I292
J 0
(2000 -500);
DISPLAY 0.978723 (2000 -500);
PAINT WHITE (2000 -500);
DISPLAY INVISIBLE (2000 -500);
FORCEPROP 2 LAST CDS_LIB dev_discrete
J 0
(1950 -650);
PAINT ORANGE (1950 -650);
DISPLAY INVISIBLE (1950 -650);
FORCEPROP 2 LAST SEC 1
J 0
(2000 -450);
DISPLAY 0.680851 (2000 -450);
PAINT MONO (2000 -450);
DISPLAY INVISIBLE (2000 -450);
FORCEPROP 2 LAST SEC_TYPE 0603V
J 0
(2000 -450);
DISPLAY 1.021277 (2000 -450);
PAINT ORANGE (2000 -450);
DISPLAY INVISIBLE (2000 -450);
FORCEPROP 2 LAST CDS_SEC 1
J 0
(2000 -500);
PAINT ORANGE (2000 -500);
DISPLAY INVISIBLE (2000 -500);
FORCEPROP 2 LAST CDS_LOCATION C4M2
J 0
(2000 -550);
DISPLAY 0.617021 (2000 -550);
PAINT AQUA (2000 -550);
DISPLAY INVISIBLE (2000 -550);
FORCEADD CAP_A..1
(2225 -650);
FORCEPROP 1 LAST MATERIAL X5R
J 0
(2275 -750);
DISPLAY 0.617021 (2275 -750);
PAINT SKYBLUE (2275 -750);
FORCEPROP 1 LAST PART_NUMBER 602433-106
J 0
(2275 -800);
DISPLAY 0.617021 (2275 -800);
PAINT BLUE (2275 -800);
FORCEPROP 1 LAST TOLERANCE 20%
J 0
(2275 -700);
DISPLAY 0.617021 (2275 -700);
PAINT SKYBLUE (2275 -700);
FORCEPROP 0 LAST GROUP PWR_MLCC_CAP
J 0
(2281 -1063);
DISPLAY 0.638298 (2281 -1063);
PAINT BROWN (2281 -1063);
DISPLAY BOTH (2281 -1063);
FORCEPROP 1 LAST VOLTAGE 4V
J 0
(2275 -650);
DISPLAY 0.617021 (2275 -650);
PAINT SKYBLUE (2275 -650);
FORCEPROP 1 LAST LOCATION C5A11
J 0
(2275 -550);
DISPLAY 0.617021 (2275 -550);
PAINT AQUA (2275 -550);
FORCEPROP 1 LASTPIN (2225 -750) $PN 2
J 0
(2235 -770);
DISPLAY 0.617021 (2235 -770);
PAINT ORANGE (2235 -770);
FORCEPROP 1 LASTPIN (2225 -550) $PN 1
J 0
(2235 -570);
DISPLAY 0.617021 (2235 -570);
PAINT ORANGE (2235 -570);
FORCEPROP 1 LAST PACK_TYPE 0603V
J 0
(2275 -850);
DISPLAY 0.617021 (2275 -850);
PAINT SKYBLUE (2275 -850);
FORCEPROP 1 LAST VALUE 47UF
J 0
(2275 -600);
DISPLAY 0.617021 (2275 -600);
PAINT SKYBLUE (2275 -600);
FORCEPROP 0 LAST BOM_SS E15431-004
J 0
(2271 -1003);
DISPLAY 0.510638 (2271 -1003);
PAINT BROWN (2271 -1003);
DISPLAY BOTH (2271 -1003);
FORCEPROP 2 LAST CDS_LIB dev_discrete
J 0
(2225 -650);
PAINT ORANGE (2225 -650);
DISPLAY INVISIBLE (2225 -650);
FORCEPROP 2 LAST SEC 1
J 0
(2275 -450);
DISPLAY 0.680851 (2275 -450);
PAINT MONO (2275 -450);
DISPLAY INVISIBLE (2275 -450);
FORCEPROP 2 LAST SEC_TYPE 0603V
J 0
(2275 -450);
DISPLAY 1.021277 (2275 -450);
PAINT ORANGE (2275 -450);
DISPLAY INVISIBLE (2275 -450);
FORCEPROP 2 LAST CDS_SEC 1
J 0
(2275 -500);
PAINT ORANGE (2275 -500);
DISPLAY INVISIBLE (2275 -500);
FORCEPROP 1 LAST PATH I293
J 0
(2275 -500);
DISPLAY 0.978723 (2275 -500);
PAINT WHITE (2275 -500);
DISPLAY INVISIBLE (2275 -500);
FORCEPROP 2 LAST CDS_LOCATION C5A11
J 0
(2275 -550);
DISPLAY 0.617021 (2275 -550);
PAINT AQUA (2275 -550);
DISPLAY INVISIBLE (2275 -550);
FORCEADD SC22U16V5MX-4-GP..1
(-500 1025);
FORCEPROP 1 LAST VALUE SC22U16V5MX-4-GP
R 1
J 0
(-425 820);
DISPLAY 0.617021 (-425 820);
PAINT GREEN (-425 820);
FORCEPROP 2 LAST TYPE X6S
J 0
(-400 950);
DISPLAY 0.638298 (-400 950);
PAINT GREEN (-400 950);
FORCEPROP 2 LAST PACK_SIZE 0805
J 0
(-400 900);
DISPLAY 0.638298 (-400 900);
PAINT GREEN (-400 900);
FORCEPROP 2 LASTPIN (-500 1100) $PN 1
R 1
J 0
(-510 1110);
DISPLAY 0.808511 (-510 1110);
PAINT ORANGE (-510 1110);
FORCEPROP 2 LAST ATTRIBUTE 22UF
J 0
(-400 1100);
DISPLAY 0.638298 (-400 1100);
PAINT GREEN (-400 1100);
FORCEPROP 2 LAST TOLERANCE 20%
J 0
(-400 1050);
DISPLAY 0.638298 (-400 1050);
PAINT GREEN (-400 1050);
FORCEPROP 1 LAST LOCATION C7W5
J 0
(-400 1160);
DISPLAY 0.617021 (-400 1160);
PAINT GREEN (-400 1160);
FORCEPROP 2 LAST RATED 16V
J 0
(-400 1000);
DISPLAY 0.638298 (-400 1000);
PAINT GREEN (-400 1000);
FORCEPROP 2 LASTPIN (-500 950) $PN 2
R 1
J 2
(-510 940);
DISPLAY 0.808511 (-510 940);
PAINT ORANGE (-510 940);
FORCEPROP 0 LAST CDS_LOCATION C7W5
J 0
(-450 1125);
PAINT MONO (-450 1125);
DISPLAY INVISIBLE (-450 1125);
FORCEPROP 1 LAST CDS_LMAN_SYM_OUTLINE -50,25,50,-25
J 0
(-500 1025);
DISPLAY 0.468085 (-500 1025);
PAINT GREEN (-500 1025);
DISPLAY INVISIBLE (-500 1025);
FORCEPROP 2 LAST CDS_LIB w_hdl
J 0
(-500 1025);
PAINT MONO (-500 1025);
DISPLAY INVISIBLE (-500 1025);
FORCEPROP 1 LAST PART_NUMBER 078.22611.0811
J 0
(-500 1025);
DISPLAY 0.617021 (-500 1025);
PAINT GREEN (-500 1025);
DISPLAY INVISIBLE (-500 1025);
FORCEPROP 2 LAST SEC_TYPE SMD-BCG5
J 0
(-475 1100);
DISPLAY 1.021277 (-475 1100);
PAINT ORANGE (-475 1100);
DISPLAY INVISIBLE (-475 1100);
FORCEPROP 2 LAST SEC 1
J 0
(-475 1100);
DISPLAY 0.680851 (-475 1100);
PAINT MONO (-475 1100);
DISPLAY INVISIBLE (-475 1100);
FORCEPROP 1 LAST PACK_TYPE SMD-BCG5
J 0
(-500 1025);
DISPLAY 0.617021 (-500 1025);
PAINT GREEN (-500 1025);
DISPLAY INVISIBLE (-500 1025);
FORCEPROP 0 LAST CDS_SEC 1
J 0
(-450 1125);
PAINT MONO (-450 1125);
DISPLAY INVISIBLE (-450 1125);
FORCEPROP 1 LAST PATH I298
J 0
(-500 1025);
DISPLAY 0.617021 (-500 1025);
PAINT GREEN (-500 1025);
DISPLAY INVISIBLE (-500 1025);
FORCEADD SC22U16V5MX-4-GP..1
(700 1025);
FORCEPROP 2 LAST TYPE X6S
J 0
(800 950);
DISPLAY 0.638298 (800 950);
PAINT GREEN (800 950);
FORCEPROP 1 LAST VALUE SC22U16V5MX-4-GP
R 1
J 0
(775 820);
DISPLAY 0.617021 (775 820);
PAINT GREEN (775 820);
FORCEPROP 2 LASTPIN (700 950) $PN 2
R 1
J 2
(690 940);
DISPLAY 0.808511 (690 940);
PAINT ORANGE (690 940);
FORCEPROP 2 LAST PACK_SIZE 0805
J 0
(800 900);
DISPLAY 0.638298 (800 900);
PAINT GREEN (800 900);
FORCEPROP 2 LASTPIN (700 1100) $PN 1
R 1
J 0
(690 1110);
DISPLAY 0.808511 (690 1110);
PAINT ORANGE (690 1110);
FORCEPROP 2 LAST RATED 16V
J 0
(800 1000);
DISPLAY 0.638298 (800 1000);
PAINT GREEN (800 1000);
FORCEPROP 2 LAST TOLERANCE 20%
J 0
(800 1050);
DISPLAY 0.638298 (800 1050);
PAINT GREEN (800 1050);
FORCEPROP 2 LAST ATTRIBUTE 22UF
J 0
(800 1100);
DISPLAY 0.638298 (800 1100);
PAINT GREEN (800 1100);
FORCEPROP 1 LAST LOCATION C7W9
J 0
(800 1160);
DISPLAY 0.617021 (800 1160);
PAINT GREEN (800 1160);
FORCEPROP 0 LAST CDS_LOCATION C7W9
J 0
(750 1125);
PAINT MONO (750 1125);
DISPLAY INVISIBLE (750 1125);
FORCEPROP 1 LAST CDS_LMAN_SYM_OUTLINE -50,25,50,-25
J 0
(700 1025);
DISPLAY 0.468085 (700 1025);
PAINT GREEN (700 1025);
DISPLAY INVISIBLE (700 1025);
FORCEPROP 2 LAST CDS_LIB w_hdl
J 0
(700 1025);
PAINT MONO (700 1025);
DISPLAY INVISIBLE (700 1025);
FORCEPROP 1 LAST PART_NUMBER 078.22611.0811
J 0
(700 1025);
DISPLAY 0.617021 (700 1025);
PAINT GREEN (700 1025);
DISPLAY INVISIBLE (700 1025);
FORCEPROP 2 LAST SEC_TYPE SMD-BCG5
J 0
(725 1100);
DISPLAY 1.021277 (725 1100);
PAINT ORANGE (725 1100);
DISPLAY INVISIBLE (725 1100);
FORCEPROP 2 LAST SEC 1
J 0
(725 1100);
DISPLAY 0.680851 (725 1100);
PAINT MONO (725 1100);
DISPLAY INVISIBLE (725 1100);
FORCEPROP 1 LAST PACK_TYPE SMD-BCG5
J 0
(700 1025);
DISPLAY 0.617021 (700 1025);
PAINT GREEN (700 1025);
DISPLAY INVISIBLE (700 1025);
FORCEPROP 0 LAST CDS_SEC 1
J 0
(750 1125);
PAINT MONO (750 1125);
DISPLAY INVISIBLE (750 1125);
FORCEPROP 1 LAST PATH I299
J 0
(700 1025);
DISPLAY 0.617021 (700 1025);
PAINT GREEN (700 1025);
DISPLAY INVISIBLE (700 1025);
FORCEADD SC22U16V5MX-4-GP..1
(400 1025);
FORCEPROP 2 LAST PACK_SIZE 0805
J 0
(500 900);
DISPLAY 0.638298 (500 900);
PAINT GREEN (500 900);
FORCEPROP 2 LAST TYPE X6S
J 0
(500 950);
DISPLAY 0.638298 (500 950);
PAINT GREEN (500 950);
FORCEPROP 2 LAST RATED 16V
J 0
(500 1000);
DISPLAY 0.638298 (500 1000);
PAINT GREEN (500 1000);
FORCEPROP 2 LAST ATTRIBUTE 22UF
J 0
(500 1100);
DISPLAY 0.638298 (500 1100);
PAINT GREEN (500 1100);
FORCEPROP 1 LAST LOCATION C7W8
J 0
(500 1160);
DISPLAY 0.617021 (500 1160);
PAINT GREEN (500 1160);
FORCEPROP 2 LASTPIN (400 1100) $PN 1
R 1
J 0
(390 1110);
DISPLAY 0.808511 (390 1110);
PAINT ORANGE (390 1110);
FORCEPROP 2 LASTPIN (400 950) $PN 2
R 1
J 2
(390 940);
DISPLAY 0.808511 (390 940);
PAINT ORANGE (390 940);
FORCEPROP 2 LAST TOLERANCE 20%
J 0
(500 1050);
DISPLAY 0.638298 (500 1050);
PAINT GREEN (500 1050);
FORCEPROP 1 LAST VALUE SC22U16V5MX-4-GP
R 1
J 0
(475 820);
DISPLAY 0.617021 (475 820);
PAINT GREEN (475 820);
FORCEPROP 0 LAST CDS_LOCATION C7W8
J 0
(450 1125);
PAINT MONO (450 1125);
DISPLAY INVISIBLE (450 1125);
FORCEPROP 1 LAST CDS_LMAN_SYM_OUTLINE -50,25,50,-25
J 0
(400 1025);
DISPLAY 0.468085 (400 1025);
PAINT GREEN (400 1025);
DISPLAY INVISIBLE (400 1025);
FORCEPROP 2 LAST CDS_LIB w_hdl
J 0
(400 1025);
PAINT MONO (400 1025);
DISPLAY INVISIBLE (400 1025);
FORCEPROP 1 LAST PART_NUMBER 078.22611.0811
J 0
(400 1025);
DISPLAY 0.617021 (400 1025);
PAINT GREEN (400 1025);
DISPLAY INVISIBLE (400 1025);
FORCEPROP 2 LAST SEC_TYPE SMD-BCG5
J 0
(425 1100);
DISPLAY 1.021277 (425 1100);
PAINT ORANGE (425 1100);
DISPLAY INVISIBLE (425 1100);
FORCEPROP 2 LAST SEC 1
J 0
(425 1100);
DISPLAY 0.680851 (425 1100);
PAINT MONO (425 1100);
DISPLAY INVISIBLE (425 1100);
FORCEPROP 1 LAST PACK_TYPE SMD-BCG5
J 0
(400 1025);
DISPLAY 0.617021 (400 1025);
PAINT GREEN (400 1025);
DISPLAY INVISIBLE (400 1025);
FORCEPROP 0 LAST CDS_SEC 1
J 0
(450 1125);
PAINT MONO (450 1125);
DISPLAY INVISIBLE (450 1125);
FORCEPROP 1 LAST PATH I300
J 0
(400 1025);
DISPLAY 0.617021 (400 1025);
PAINT GREEN (400 1025);
DISPLAY INVISIBLE (400 1025);
FORCEADD SC22U16V5MX-4-GP..1
(100 1025);
FORCEPROP 1 LAST VALUE SC22U16V5MX-4-GP
R 1
J 0
(175 820);
DISPLAY 0.617021 (175 820);
PAINT GREEN (175 820);
FORCEPROP 2 LAST PACK_SIZE 0805
J 0
(200 900);
DISPLAY 0.638298 (200 900);
PAINT GREEN (200 900);
FORCEPROP 2 LAST RATED 16V
J 0
(200 1000);
DISPLAY 0.638298 (200 1000);
PAINT GREEN (200 1000);
FORCEPROP 2 LAST ATTRIBUTE 22UF
J 0
(200 1100);
DISPLAY 0.638298 (200 1100);
PAINT GREEN (200 1100);
FORCEPROP 2 LASTPIN (100 1100) $PN 1
R 1
J 0
(90 1110);
DISPLAY 0.808511 (90 1110);
PAINT ORANGE (90 1110);
FORCEPROP 1 LAST LOCATION C7W7
J 0
(200 1160);
DISPLAY 0.617021 (200 1160);
PAINT GREEN (200 1160);
FORCEPROP 2 LAST TOLERANCE 20%
J 0
(200 1050);
DISPLAY 0.638298 (200 1050);
PAINT GREEN (200 1050);
FORCEPROP 2 LASTPIN (100 950) $PN 2
R 1
J 2
(90 940);
DISPLAY 0.808511 (90 940);
PAINT ORANGE (90 940);
FORCEPROP 2 LAST TYPE X6S
J 0
(200 950);
DISPLAY 0.638298 (200 950);
PAINT GREEN (200 950);
FORCEPROP 1 LAST PATH I301
J 0
(100 1025);
DISPLAY 0.617021 (100 1025);
PAINT GREEN (100 1025);
DISPLAY INVISIBLE (100 1025);
FORCEPROP 0 LAST CDS_SEC 1
J 0
(150 1125);
PAINT MONO (150 1125);
DISPLAY INVISIBLE (150 1125);
FORCEPROP 1 LAST PACK_TYPE SMD-BCG5
J 0
(100 1025);
DISPLAY 0.617021 (100 1025);
PAINT GREEN (100 1025);
DISPLAY INVISIBLE (100 1025);
FORCEPROP 2 LAST SEC 1
J 0
(125 1100);
DISPLAY 0.680851 (125 1100);
PAINT MONO (125 1100);
DISPLAY INVISIBLE (125 1100);
FORCEPROP 2 LAST SEC_TYPE SMD-BCG5
J 0
(125 1100);
DISPLAY 1.021277 (125 1100);
PAINT ORANGE (125 1100);
DISPLAY INVISIBLE (125 1100);
FORCEPROP 1 LAST PART_NUMBER 078.22611.0811
J 0
(100 1025);
DISPLAY 0.617021 (100 1025);
PAINT GREEN (100 1025);
DISPLAY INVISIBLE (100 1025);
FORCEPROP 2 LAST CDS_LIB w_hdl
J 0
(100 1025);
PAINT MONO (100 1025);
DISPLAY INVISIBLE (100 1025);
FORCEPROP 1 LAST CDS_LMAN_SYM_OUTLINE -50,25,50,-25
J 0
(100 1025);
DISPLAY 0.468085 (100 1025);
PAINT GREEN (100 1025);
DISPLAY INVISIBLE (100 1025);
FORCEPROP 0 LAST CDS_LOCATION C7W7
J 0
(150 1125);
PAINT MONO (150 1125);
DISPLAY INVISIBLE (150 1125);
FORCEADD SC22U16V5MX-4-GP..1
(-200 1025);
FORCEPROP 1 LAST VALUE SC22U16V5MX-4-GP
R 1
J 0
(-125 820);
DISPLAY 0.617021 (-125 820);
PAINT GREEN (-125 820);
FORCEPROP 2 LAST TYPE X6S
J 0
(-100 950);
DISPLAY 0.638298 (-100 950);
PAINT GREEN (-100 950);
FORCEPROP 2 LASTPIN (-200 950) $PN 2
R 1
J 2
(-210 940);
DISPLAY 0.808511 (-210 940);
PAINT ORANGE (-210 940);
FORCEPROP 2 LASTPIN (-200 1100) $PN 1
R 1
J 0
(-210 1110);
DISPLAY 0.808511 (-210 1110);
PAINT ORANGE (-210 1110);
FORCEPROP 1 LAST LOCATION C7W6
J 0
(-100 1160);
DISPLAY 0.617021 (-100 1160);
PAINT GREEN (-100 1160);
FORCEPROP 2 LAST ATTRIBUTE 22UF
J 0
(-100 1100);
DISPLAY 0.638298 (-100 1100);
PAINT GREEN (-100 1100);
FORCEPROP 2 LAST TOLERANCE 20%
J 0
(-100 1050);
DISPLAY 0.638298 (-100 1050);
PAINT GREEN (-100 1050);
FORCEPROP 2 LAST PACK_SIZE 0805
J 0
(-100 900);
DISPLAY 0.638298 (-100 900);
PAINT GREEN (-100 900);
FORCEPROP 2 LAST RATED 16V
J 0
(-100 1000);
DISPLAY 0.638298 (-100 1000);
PAINT GREEN (-100 1000);
FORCEPROP 0 LAST CDS_LOCATION C7W6
J 0
(-150 1125);
PAINT MONO (-150 1125);
DISPLAY INVISIBLE (-150 1125);
FORCEPROP 1 LAST CDS_LMAN_SYM_OUTLINE -50,25,50,-25
J 0
(-200 1025);
DISPLAY 0.468085 (-200 1025);
PAINT GREEN (-200 1025);
DISPLAY INVISIBLE (-200 1025);
FORCEPROP 2 LAST CDS_LIB w_hdl
J 0
(-200 1025);
PAINT MONO (-200 1025);
DISPLAY INVISIBLE (-200 1025);
FORCEPROP 1 LAST PART_NUMBER 078.22611.0811
J 0
(-200 1025);
DISPLAY 0.617021 (-200 1025);
PAINT GREEN (-200 1025);
DISPLAY INVISIBLE (-200 1025);
FORCEPROP 2 LAST SEC_TYPE SMD-BCG5
J 0
(-175 1100);
DISPLAY 1.021277 (-175 1100);
PAINT ORANGE (-175 1100);
DISPLAY INVISIBLE (-175 1100);
FORCEPROP 2 LAST SEC 1
J 0
(-175 1100);
DISPLAY 0.680851 (-175 1100);
PAINT MONO (-175 1100);
DISPLAY INVISIBLE (-175 1100);
FORCEPROP 1 LAST PACK_TYPE SMD-BCG5
J 0
(-200 1025);
DISPLAY 0.617021 (-200 1025);
PAINT GREEN (-200 1025);
DISPLAY INVISIBLE (-200 1025);
FORCEPROP 0 LAST CDS_SEC 1
J 0
(-150 1125);
PAINT MONO (-150 1125);
DISPLAY INVISIBLE (-150 1125);
FORCEPROP 1 LAST PATH I302
J 0
(-200 1025);
DISPLAY 0.617021 (-200 1025);
PAINT GREEN (-200 1025);
DISPLAY INVISIBLE (-200 1025);
FORCEADD SC22U16V5MX-4-GP..1
(1900 1025);
FORCEPROP 2 LAST RATED 16V
J 0
(2000 1000);
DISPLAY 0.638298 (2000 1000);
PAINT GREEN (2000 1000);
FORCEPROP 1 LAST VALUE SC22U16V5MX-4-GP
R 1
J 0
(1975 820);
DISPLAY 0.617021 (1975 820);
PAINT GREEN (1975 820);
FORCEPROP 2 LASTPIN (1900 1100) $PN 1
R 1
J 0
(1890 1110);
DISPLAY 0.808511 (1890 1110);
PAINT ORANGE (1890 1110);
FORCEPROP 2 LASTPIN (1900 950) $PN 2
R 1
J 2
(1890 940);
DISPLAY 0.808511 (1890 940);
PAINT ORANGE (1890 940);
FORCEPROP 2 LAST TOLERANCE 20%
J 0
(2000 1050);
DISPLAY 0.638298 (2000 1050);
PAINT GREEN (2000 1050);
FORCEPROP 2 LAST TYPE X6S
J 0
(2000 950);
DISPLAY 0.638298 (2000 950);
PAINT GREEN (2000 950);
FORCEPROP 2 LAST PACK_SIZE 0805
J 0
(2000 900);
DISPLAY 0.638298 (2000 900);
PAINT GREEN (2000 900);
FORCEPROP 1 LAST LOCATION C7W13
J 0
(2000 1160);
DISPLAY 0.617021 (2000 1160);
PAINT GREEN (2000 1160);
FORCEPROP 2 LAST ATTRIBUTE 22UF
J 0
(2000 1100);
DISPLAY 0.638298 (2000 1100);
PAINT GREEN (2000 1100);
FORCEPROP 0 LAST CDS_LOCATION C7W13
J 0
(1950 1125);
PAINT MONO (1950 1125);
DISPLAY INVISIBLE (1950 1125);
FORCEPROP 1 LAST CDS_LMAN_SYM_OUTLINE -50,25,50,-25
J 0
(1900 1025);
DISPLAY 0.468085 (1900 1025);
PAINT GREEN (1900 1025);
DISPLAY INVISIBLE (1900 1025);
FORCEPROP 2 LAST CDS_LIB w_hdl
J 0
(1900 1025);
PAINT MONO (1900 1025);
DISPLAY INVISIBLE (1900 1025);
FORCEPROP 1 LAST PART_NUMBER 078.22611.0811
J 0
(1900 1025);
DISPLAY 0.617021 (1900 1025);
PAINT GREEN (1900 1025);
DISPLAY INVISIBLE (1900 1025);
FORCEPROP 2 LAST SEC_TYPE SMD-BCG5
J 0
(1925 1100);
DISPLAY 1.021277 (1925 1100);
PAINT ORANGE (1925 1100);
DISPLAY INVISIBLE (1925 1100);
FORCEPROP 2 LAST SEC 1
J 0
(1925 1100);
DISPLAY 0.680851 (1925 1100);
PAINT MONO (1925 1100);
DISPLAY INVISIBLE (1925 1100);
FORCEPROP 1 LAST PACK_TYPE SMD-BCG5
J 0
(1900 1025);
DISPLAY 0.617021 (1900 1025);
PAINT GREEN (1900 1025);
DISPLAY INVISIBLE (1900 1025);
FORCEPROP 0 LAST CDS_SEC 1
J 0
(1950 1125);
PAINT MONO (1950 1125);
DISPLAY INVISIBLE (1950 1125);
FORCEPROP 1 LAST PATH I303
J 0
(1900 1025);
DISPLAY 0.617021 (1900 1025);
PAINT GREEN (1900 1025);
DISPLAY INVISIBLE (1900 1025);
FORCEADD SC22U16V5MX-4-GP..1
(1600 1025);
FORCEPROP 2 LAST RATED 16V
J 0
(1700 1000);
DISPLAY 0.638298 (1700 1000);
PAINT GREEN (1700 1000);
FORCEPROP 1 LAST VALUE SC22U16V5MX-4-GP
R 1
J 0
(1675 820);
DISPLAY 0.617021 (1675 820);
PAINT GREEN (1675 820);
FORCEPROP 2 LASTPIN (1600 950) $PN 2
R 1
J 2
(1590 940);
DISPLAY 0.808511 (1590 940);
PAINT ORANGE (1590 940);
FORCEPROP 2 LAST TOLERANCE 20%
J 0
(1700 1050);
DISPLAY 0.638298 (1700 1050);
PAINT GREEN (1700 1050);
FORCEPROP 2 LASTPIN (1600 1100) $PN 1
R 1
J 0
(1590 1110);
DISPLAY 0.808511 (1590 1110);
PAINT ORANGE (1590 1110);
FORCEPROP 2 LAST PACK_SIZE 0805
J 0
(1700 900);
DISPLAY 0.638298 (1700 900);
PAINT GREEN (1700 900);
FORCEPROP 1 LAST LOCATION C7W12
J 0
(1700 1160);
DISPLAY 0.617021 (1700 1160);
PAINT GREEN (1700 1160);
FORCEPROP 2 LAST ATTRIBUTE 22UF
J 0
(1700 1100);
DISPLAY 0.638298 (1700 1100);
PAINT GREEN (1700 1100);
FORCEPROP 2 LAST TYPE X6S
J 0
(1700 950);
DISPLAY 0.638298 (1700 950);
PAINT GREEN (1700 950);
FORCEPROP 1 LAST PATH I304
J 0
(1600 1025);
DISPLAY 0.617021 (1600 1025);
PAINT GREEN (1600 1025);
DISPLAY INVISIBLE (1600 1025);
FORCEPROP 0 LAST CDS_SEC 1
J 0
(1650 1125);
PAINT MONO (1650 1125);
DISPLAY INVISIBLE (1650 1125);
FORCEPROP 1 LAST PACK_TYPE SMD-BCG5
J 0
(1600 1025);
DISPLAY 0.617021 (1600 1025);
PAINT GREEN (1600 1025);
DISPLAY INVISIBLE (1600 1025);
FORCEPROP 2 LAST SEC 1
J 0
(1625 1100);
DISPLAY 0.680851 (1625 1100);
PAINT MONO (1625 1100);
DISPLAY INVISIBLE (1625 1100);
FORCEPROP 2 LAST SEC_TYPE SMD-BCG5
J 0
(1625 1100);
DISPLAY 1.021277 (1625 1100);
PAINT ORANGE (1625 1100);
DISPLAY INVISIBLE (1625 1100);
FORCEPROP 1 LAST PART_NUMBER 078.22611.0811
J 0
(1600 1025);
DISPLAY 0.617021 (1600 1025);
PAINT GREEN (1600 1025);
DISPLAY INVISIBLE (1600 1025);
FORCEPROP 2 LAST CDS_LIB w_hdl
J 0
(1600 1025);
PAINT MONO (1600 1025);
DISPLAY INVISIBLE (1600 1025);
FORCEPROP 1 LAST CDS_LMAN_SYM_OUTLINE -50,25,50,-25
J 0
(1600 1025);
DISPLAY 0.468085 (1600 1025);
PAINT GREEN (1600 1025);
DISPLAY INVISIBLE (1600 1025);
FORCEPROP 0 LAST CDS_LOCATION C7W12
J 0
(1650 1125);
PAINT MONO (1650 1125);
DISPLAY INVISIBLE (1650 1125);
FORCEADD SC22U16V5MX-4-GP..1
(1300 1025);
FORCEPROP 2 LAST RATED 16V
J 0
(1400 1000);
DISPLAY 0.638298 (1400 1000);
PAINT GREEN (1400 1000);
FORCEPROP 1 LAST VALUE SC22U16V5MX-4-GP
R 1
J 0
(1375 820);
DISPLAY 0.617021 (1375 820);
PAINT GREEN (1375 820);
FORCEPROP 2 LAST ATTRIBUTE 22UF
J 0
(1400 1100);
DISPLAY 0.638298 (1400 1100);
PAINT GREEN (1400 1100);
FORCEPROP 1 LAST LOCATION C7W11
J 0
(1400 1160);
DISPLAY 0.617021 (1400 1160);
PAINT GREEN (1400 1160);
FORCEPROP 2 LAST TYPE X6S
J 0
(1400 950);
DISPLAY 0.638298 (1400 950);
PAINT GREEN (1400 950);
FORCEPROP 2 LASTPIN (1300 950) $PN 2
R 1
J 2
(1290 940);
DISPLAY 0.808511 (1290 940);
PAINT ORANGE (1290 940);
FORCEPROP 2 LAST PACK_SIZE 0805
J 0
(1400 900);
DISPLAY 0.638298 (1400 900);
PAINT GREEN (1400 900);
FORCEPROP 2 LASTPIN (1300 1100) $PN 1
R 1
J 0
(1290 1110);
DISPLAY 0.808511 (1290 1110);
PAINT ORANGE (1290 1110);
FORCEPROP 2 LAST TOLERANCE 20%
J 0
(1400 1050);
DISPLAY 0.638298 (1400 1050);
PAINT GREEN (1400 1050);
FORCEPROP 1 LAST PATH I305
J 0
(1300 1025);
DISPLAY 0.617021 (1300 1025);
PAINT GREEN (1300 1025);
DISPLAY INVISIBLE (1300 1025);
FORCEPROP 0 LAST CDS_SEC 1
J 0
(1350 1125);
PAINT MONO (1350 1125);
DISPLAY INVISIBLE (1350 1125);
FORCEPROP 1 LAST PACK_TYPE SMD-BCG5
J 0
(1300 1025);
DISPLAY 0.617021 (1300 1025);
PAINT GREEN (1300 1025);
DISPLAY INVISIBLE (1300 1025);
FORCEPROP 2 LAST SEC 1
J 0
(1325 1100);
DISPLAY 0.680851 (1325 1100);
PAINT MONO (1325 1100);
DISPLAY INVISIBLE (1325 1100);
FORCEPROP 2 LAST SEC_TYPE SMD-BCG5
J 0
(1325 1100);
DISPLAY 1.021277 (1325 1100);
PAINT ORANGE (1325 1100);
DISPLAY INVISIBLE (1325 1100);
FORCEPROP 1 LAST PART_NUMBER 078.22611.0811
J 0
(1300 1025);
DISPLAY 0.617021 (1300 1025);
PAINT GREEN (1300 1025);
DISPLAY INVISIBLE (1300 1025);
FORCEPROP 2 LAST CDS_LIB w_hdl
J 0
(1300 1025);
PAINT MONO (1300 1025);
DISPLAY INVISIBLE (1300 1025);
FORCEPROP 1 LAST CDS_LMAN_SYM_OUTLINE -50,25,50,-25
J 0
(1300 1025);
DISPLAY 0.468085 (1300 1025);
PAINT GREEN (1300 1025);
DISPLAY INVISIBLE (1300 1025);
FORCEPROP 0 LAST CDS_LOCATION C7W11
J 0
(1350 1125);
PAINT MONO (1350 1125);
DISPLAY INVISIBLE (1350 1125);
FORCEADD SC22U16V5MX-4-GP..1
(1000 1025);
FORCEPROP 1 LAST VALUE SC22U16V5MX-4-GP
R 1
J 0
(1075 820);
DISPLAY 0.617021 (1075 820);
PAINT GREEN (1075 820);
FORCEPROP 2 LAST RATED 16V
J 0
(1100 1000);
DISPLAY 0.638298 (1100 1000);
PAINT GREEN (1100 1000);
FORCEPROP 1 LAST LOCATION C7W10
J 0
(1100 1160);
DISPLAY 0.617021 (1100 1160);
PAINT GREEN (1100 1160);
FORCEPROP 2 LASTPIN (1000 950) $PN 2
R 1
J 2
(990 940);
DISPLAY 0.808511 (990 940);
PAINT ORANGE (990 940);
FORCEPROP 2 LASTPIN (1000 1100) $PN 1
R 1
J 0
(990 1110);
DISPLAY 0.808511 (990 1110);
PAINT ORANGE (990 1110);
FORCEPROP 2 LAST ATTRIBUTE 22UF
J 0
(1100 1100);
DISPLAY 0.638298 (1100 1100);
PAINT GREEN (1100 1100);
FORCEPROP 2 LAST TOLERANCE 20%
J 0
(1100 1050);
DISPLAY 0.638298 (1100 1050);
PAINT GREEN (1100 1050);
FORCEPROP 2 LAST TYPE X6S
J 0
(1100 950);
DISPLAY 0.638298 (1100 950);
PAINT GREEN (1100 950);
FORCEPROP 2 LAST PACK_SIZE 0805
J 0
(1100 900);
DISPLAY 0.638298 (1100 900);
PAINT GREEN (1100 900);
FORCEPROP 0 LAST CDS_LOCATION C7W10
J 0
(1050 1125);
PAINT MONO (1050 1125);
DISPLAY INVISIBLE (1050 1125);
FORCEPROP 1 LAST CDS_LMAN_SYM_OUTLINE -50,25,50,-25
J 0
(1000 1025);
DISPLAY 0.468085 (1000 1025);
PAINT GREEN (1000 1025);
DISPLAY INVISIBLE (1000 1025);
FORCEPROP 2 LAST CDS_LIB w_hdl
J 0
(1000 1025);
PAINT MONO (1000 1025);
DISPLAY INVISIBLE (1000 1025);
FORCEPROP 1 LAST PART_NUMBER 078.22611.0811
J 0
(1000 1025);
DISPLAY 0.617021 (1000 1025);
PAINT GREEN (1000 1025);
DISPLAY INVISIBLE (1000 1025);
FORCEPROP 2 LAST SEC_TYPE SMD-BCG5
J 0
(1025 1100);
DISPLAY 1.021277 (1025 1100);
PAINT ORANGE (1025 1100);
DISPLAY INVISIBLE (1025 1100);
FORCEPROP 2 LAST SEC 1
J 0
(1025 1100);
DISPLAY 0.680851 (1025 1100);
PAINT MONO (1025 1100);
DISPLAY INVISIBLE (1025 1100);
FORCEPROP 1 LAST PACK_TYPE SMD-BCG5
J 0
(1000 1025);
DISPLAY 0.617021 (1000 1025);
PAINT GREEN (1000 1025);
DISPLAY INVISIBLE (1000 1025);
FORCEPROP 0 LAST CDS_SEC 1
J 0
(1050 1125);
PAINT MONO (1050 1125);
DISPLAY INVISIBLE (1050 1125);
FORCEPROP 1 LAST PATH I306
J 0
(1000 1025);
DISPLAY 0.617021 (1000 1025);
PAINT GREEN (1000 1025);
DISPLAY INVISIBLE (1000 1025);
FORCEADD GND..1
(1900 725);
FORCEPROP 3 LASTPIN (1900 775) SIG_NAME GND\g
J 0
(1910 785);
DISPLAY 0.659574 (1910 785);
PAINT MONO (1910 785);
DISPLAY INVISIBLE (1910 785);
FORCEPROP 1 LAST HDL_POWER GND
J 0
(1900 875);
DISPLAY 0.893617 (1900 875);
PAINT GREEN (1900 875);
DISPLAY INVISIBLE (1900 875);
FORCEPROP 1 LAST BODY_TYPE PLUMBING
J 0
(1855 682);
DISPLAY 0.340426 (1855 682);
PAINT GREEN (1855 682);
DISPLAY INVISIBLE (1855 682);
FORCEPROP 1 LAST SIZE 1B
J 0
(1975 675);
DISPLAY 0.893617 (1975 675);
PAINT GREEN (1975 675);
DISPLAY INVISIBLE (1975 675);
FORCEPROP 1 LAST VOLTAGE 0
J 0
(1900 725);
PAINT SKYBLUE (1900 725);
DISPLAY INVISIBLE (1900 725);
FORCEPROP 2 LAST CDS_LIB mstr_symbols
J 0
(1900 725);
PAINT ORANGE (1900 725);
DISPLAY INVISIBLE (1900 725);
FORCEPROP 2 LAST BOM_COST MEM_VRD_PVDDQ_DEF
J 0
(1575 800);
PAINT MONO (1575 800);
DISPLAY INVISIBLE (1575 800);
FORCEPROP 2 LAST ROOM VDDQ_DEF_PWR_VR
J 0
(1350 800);
PAINT ORANGE (1350 800);
DISPLAY INVISIBLE (1350 800);
FORCEPROP 1 LAST PATH I307
J 0
(1975 725);
DISPLAY 0.872340 (1975 725);
PAINT AQUA (1975 725);
DISPLAY INVISIBLE (1975 725);
FORCEADD CAP..1
(2750 2825);
FORCEPROP 0 LAST NEW_PN 078.1071T.M002
J 0
(2803 2416);
DISPLAY 0.638298 (2803 2416);
PAINT BROWN (2803 2416);
DISPLAY BOTH (2803 2416);
FORCEPROP 1 LAST TOLERANCE 20%
J 0
(2800 2775);
DISPLAY 0.617021 (2800 2775);
PAINT SKYBLUE (2800 2775);
FORCEPROP 1 LAST VOLTAGE 4V
J 0
(2800 2825);
DISPLAY 0.617021 (2800 2825);
PAINT SKYBLUE (2800 2825);
FORCEPROP 0 LAST NEW_MATERIAL X6S
J 0
(2800 2350);
DISPLAY 0.638298 (2800 2350);
PAINT BROWN (2800 2350);
DISPLAY BOTH (2800 2350);
FORCEPROP 1 LASTPIN (2750 2725) $PN 2
J 0
(2760 2705);
DISPLAY 0.617021 (2760 2705);
PAINT ORANGE (2760 2705);
FORCEPROP 1 LAST PART_NUMBER 602433-112
J 0
(2800 2725);
DISPLAY 0.617021 (2800 2725);
PAINT BLUE (2800 2725);
FORCEPROP 1 LASTPIN (2750 2925) $PN 1
J 0
(2760 2905);
DISPLAY 0.617021 (2760 2905);
PAINT ORANGE (2760 2905);
FORCEPROP 1 LAST VALUE 100UF
J 0
(2800 2875);
DISPLAY 0.617021 (2800 2875);
PAINT SKYBLUE (2800 2875);
FORCEPROP 0 LAST BOM_SS NOPOP
J 0
(2800 2300);
DISPLAY 0.638298 (2800 2300);
PAINT BROWN (2800 2300);
DISPLAY BOTH (2800 2300);
FORCEPROP 1 LAST LOCATION C5A20
J 0
(2800 2925);
DISPLAY 0.617021 (2800 2925);
PAINT AQUA (2800 2925);
FORCEPROP 0 LAST GROUP PWR_MLCC_CAP
J 0
(2806 2262);
DISPLAY 0.638298 (2806 2262);
PAINT BROWN (2806 2262);
DISPLAY BOTH (2806 2262);
FORCEPROP 1 LAST PACK_TYPE 0805
J 0
(2800 2675);
DISPLAY 0.617021 (2800 2675);
PAINT SKYBLUE (2800 2675);
FORCEPROP 1 LAST PATH I308
J 0
(2800 2975);
DISPLAY 0.978723 (2800 2975);
PAINT WHITE (2800 2975);
DISPLAY INVISIBLE (2800 2975);
FORCEPROP 0 LAST CDS_SEC 1
J 0
(2800 2975);
PAINT MONO (2800 2975);
DISPLAY INVISIBLE (2800 2975);
FORCEPROP 2 LAST CDS_LIB mstr_discrete
J 0
(2750 2825);
PAINT MONO (2750 2825);
DISPLAY INVISIBLE (2750 2825);
FORCEPROP 2 LAST BOM_COST MEM_VRD_PVDDQ_CD
J 0
(2800 2975);
PAINT MONO (2800 2975);
DISPLAY INVISIBLE (2800 2975);
FORCEPROP 2 LAST ROOM VDDQ_ABC_PWR_VR
J 0
(2800 2975);
PAINT MONO (2800 2975);
DISPLAY INVISIBLE (2800 2975);
FORCEPROP 2 LAST SEC_TYPE 0805
J 0
(2800 3025);
DISPLAY 1.021277 (2800 3025);
PAINT ORANGE (2800 3025);
DISPLAY INVISIBLE (2800 3025);
FORCEPROP 2 LAST SEC 1
J 0
(2800 3025);
DISPLAY 0.680851 (2800 3025);
PAINT MONO (2800 3025);
DISPLAY INVISIBLE (2800 3025);
FORCEPROP 1 LAST MATERIAL X5R
J 0
(2800 2725);
DISPLAY 0.617021 (2800 2725);
PAINT SKYBLUE (2800 2725);
DISPLAY INVISIBLE (2800 2725);
FORCEPROP 2 LAST CDS_LOCATION C5A20
J 0
(2800 2925);
DISPLAY 0.617021 (2800 2925);
PAINT AQUA (2800 2925);
DISPLAY INVISIBLE (2800 2925);
FORCEADD CAP..1
(3150 2825);
FORCEPROP 0 LAST NEW_PN 078.1071T.M002
J 0
(3195 2629);
DISPLAY 0.638298 (3195 2629);
PAINT BROWN (3195 2629);
DISPLAY BOTH (3195 2629);
FORCEPROP 1 LAST LOCATION C5L1
J 0
(3200 2925);
DISPLAY 0.617021 (3200 2925);
PAINT AQUA (3200 2925);
FORCEPROP 1 LASTPIN (3150 2925) $PN 1
J 0
(3160 2905);
DISPLAY 0.617021 (3160 2905);
PAINT ORANGE (3160 2905);
FORCEPROP 1 LASTPIN (3150 2725) $PN 2
J 0
(3160 2705);
DISPLAY 0.617021 (3160 2705);
PAINT ORANGE (3160 2705);
FORCEPROP 1 LAST VOLTAGE 4V
J 0
(3200 2825);
DISPLAY 0.617021 (3200 2825);
PAINT SKYBLUE (3200 2825);
FORCEPROP 1 LAST TOLERANCE 20%
J 0
(3200 2775);
DISPLAY 0.617021 (3200 2775);
PAINT SKYBLUE (3200 2775);
FORCEPROP 1 LAST PACK_TYPE 0805
J 0
(3200 2675);
DISPLAY 0.617021 (3200 2675);
PAINT SKYBLUE (3200 2675);
FORCEPROP 1 LAST VALUE 100UF
J 0
(3200 2875);
DISPLAY 0.617021 (3200 2875);
PAINT SKYBLUE (3200 2875);
FORCEPROP 1 LAST PART_NUMBER 602433-112
J 0
(3200 2725);
DISPLAY 0.617021 (3200 2725);
PAINT BLUE (3200 2725);
FORCEPROP 0 LAST NEW_MATERIAL X6S
J 0
(3200 2575);
DISPLAY 0.638298 (3200 2575);
PAINT BROWN (3200 2575);
DISPLAY BOTH (3200 2575);
FORCEPROP 0 LAST BOM_SS NOPOP
J 0
(3200 2525);
DISPLAY 0.638298 (3200 2525);
PAINT BROWN (3200 2525);
DISPLAY BOTH (3200 2525);
FORCEPROP 0 LAST GROUP PWR_MLCC_CAP
J 0
(3206 2487);
DISPLAY 0.638298 (3206 2487);
PAINT BROWN (3206 2487);
DISPLAY BOTH (3206 2487);
FORCEPROP 1 LAST PATH I309
J 0
(3200 2975);
DISPLAY 0.978723 (3200 2975);
PAINT WHITE (3200 2975);
DISPLAY INVISIBLE (3200 2975);
FORCEPROP 1 LAST MATERIAL X5R
J 0
(3200 2725);
DISPLAY 0.617021 (3200 2725);
PAINT SKYBLUE (3200 2725);
DISPLAY INVISIBLE (3200 2725);
FORCEPROP 2 LAST SEC 1
J 0
(3200 3025);
DISPLAY 0.680851 (3200 3025);
PAINT MONO (3200 3025);
DISPLAY INVISIBLE (3200 3025);
FORCEPROP 2 LAST SEC_TYPE 0805
J 0
(3200 3025);
DISPLAY 1.021277 (3200 3025);
PAINT ORANGE (3200 3025);
DISPLAY INVISIBLE (3200 3025);
FORCEPROP 2 LAST ROOM VDDQ_ABC_PWR_VR
J 0
(3200 2975);
PAINT MONO (3200 2975);
DISPLAY INVISIBLE (3200 2975);
FORCEPROP 2 LAST BOM_COST MEM_VRD_PVDDQ_CD
J 0
(3200 2975);
PAINT MONO (3200 2975);
DISPLAY INVISIBLE (3200 2975);
FORCEPROP 2 LAST CDS_LIB mstr_discrete
J 0
(3150 2825);
PAINT MONO (3150 2825);
DISPLAY INVISIBLE (3150 2825);
FORCEPROP 0 LAST CDS_SEC 1
J 0
(3200 2975);
PAINT MONO (3200 2975);
DISPLAY INVISIBLE (3200 2975);
FORCEPROP 2 LAST CDS_LOCATION C5L1
J 0
(3200 2925);
DISPLAY 0.617021 (3200 2925);
PAINT AQUA (3200 2925);
DISPLAY INVISIBLE (3200 2925);
FORCEADD CAP..1
(3850 2825);
FORCEPROP 0 LAST NEW_PN 078.1071T.M002
J 0
(3892 2636);
DISPLAY 0.638298 (3892 2636);
PAINT BROWN (3892 2636);
DISPLAY BOTH (3892 2636);
FORCEPROP 1 LASTPIN (3850 2725) $PN 2
J 0
(3860 2705);
DISPLAY 0.617021 (3860 2705);
PAINT ORANGE (3860 2705);
FORCEPROP 1 LAST LOCATION C5L3
J 0
(3900 2925);
DISPLAY 0.617021 (3900 2925);
PAINT AQUA (3900 2925);
FORCEPROP 1 LAST VOLTAGE 4V
J 0
(3900 2825);
DISPLAY 0.617021 (3900 2825);
PAINT SKYBLUE (3900 2825);
FORCEPROP 1 LASTPIN (3850 2925) $PN 1
J 0
(3860 2905);
DISPLAY 0.617021 (3860 2905);
PAINT ORANGE (3860 2905);
FORCEPROP 1 LAST VALUE 100UF
J 0
(3900 2875);
DISPLAY 0.617021 (3900 2875);
PAINT SKYBLUE (3900 2875);
FORCEPROP 1 LAST TOLERANCE 20%
J 0
(3900 2775);
DISPLAY 0.617021 (3900 2775);
PAINT SKYBLUE (3900 2775);
FORCEPROP 1 LAST PART_NUMBER 602433-112
J 0
(3900 2725);
DISPLAY 0.617021 (3900 2725);
PAINT BLUE (3900 2725);
FORCEPROP 1 LAST PACK_TYPE 0805
J 0
(3900 2675);
DISPLAY 0.617021 (3900 2675);
PAINT SKYBLUE (3900 2675);
FORCEPROP 0 LAST NEW_MATERIAL X6S
J 0
(3900 2575);
DISPLAY 0.638298 (3900 2575);
PAINT BROWN (3900 2575);
DISPLAY BOTH (3900 2575);
FORCEPROP 0 LAST BOM_SS NOPOP
J 0
(3900 2525);
DISPLAY 0.638298 (3900 2525);
PAINT BROWN (3900 2525);
DISPLAY BOTH (3900 2525);
FORCEPROP 0 LAST GROUP PWR_MLCC_CAP
J 0
(3906 2462);
DISPLAY 0.638298 (3906 2462);
PAINT BROWN (3906 2462);
DISPLAY BOTH (3906 2462);
FORCEPROP 1 LAST MATERIAL X5R
J 0
(3900 2725);
DISPLAY 0.617021 (3900 2725);
PAINT SKYBLUE (3900 2725);
DISPLAY INVISIBLE (3900 2725);
FORCEPROP 2 LAST SEC 1
J 0
(3900 3025);
DISPLAY 0.680851 (3900 3025);
PAINT MONO (3900 3025);
DISPLAY INVISIBLE (3900 3025);
FORCEPROP 2 LAST SEC_TYPE 0805
J 0
(3900 3025);
DISPLAY 1.021277 (3900 3025);
PAINT ORANGE (3900 3025);
DISPLAY INVISIBLE (3900 3025);
FORCEPROP 2 LAST ROOM VDDQ_ABC_PWR_VR
J 0
(3900 2975);
PAINT MONO (3900 2975);
DISPLAY INVISIBLE (3900 2975);
FORCEPROP 2 LAST BOM_COST MEM_VRD_PVDDQ_CD
J 0
(3900 2975);
PAINT MONO (3900 2975);
DISPLAY INVISIBLE (3900 2975);
FORCEPROP 2 LAST CDS_LIB mstr_discrete
J 0
(3850 2825);
PAINT MONO (3850 2825);
DISPLAY INVISIBLE (3850 2825);
FORCEPROP 0 LAST CDS_SEC 1
J 0
(3900 2975);
PAINT MONO (3900 2975);
DISPLAY INVISIBLE (3900 2975);
FORCEPROP 1 LAST PATH I310
J 0
(3900 2975);
DISPLAY 0.978723 (3900 2975);
PAINT WHITE (3900 2975);
DISPLAY INVISIBLE (3900 2975);
FORCEPROP 2 LAST CDS_LOCATION C5L3
J 0
(3900 2925);
DISPLAY 0.617021 (3900 2925);
PAINT AQUA (3900 2925);
DISPLAY INVISIBLE (3900 2925);
FORCEADD CAP..1
(3500 2825);
FORCEPROP 0 LAST NEW_PN 078.1071T.M002
J 0
(3543 2393);
DISPLAY 0.638298 (3543 2393);
PAINT BROWN (3543 2393);
DISPLAY BOTH (3543 2393);
FORCEPROP 1 LAST PART_NUMBER 602433-112
J 0
(3550 2725);
DISPLAY 0.617021 (3550 2725);
PAINT BLUE (3550 2725);
FORCEPROP 1 LAST TOLERANCE 20%
J 0
(3550 2775);
DISPLAY 0.617021 (3550 2775);
PAINT SKYBLUE (3550 2775);
FORCEPROP 1 LAST VALUE 100UF
J 0
(3550 2875);
DISPLAY 0.617021 (3550 2875);
PAINT SKYBLUE (3550 2875);
FORCEPROP 1 LAST VOLTAGE 4V
J 0
(3550 2825);
DISPLAY 0.617021 (3550 2825);
PAINT SKYBLUE (3550 2825);
FORCEPROP 1 LAST PACK_TYPE 0805
J 0
(3550 2675);
DISPLAY 0.617021 (3550 2675);
PAINT SKYBLUE (3550 2675);
FORCEPROP 0 LAST NEW_MATERIAL X6S
J 0
(3550 2350);
DISPLAY 0.638298 (3550 2350);
PAINT BROWN (3550 2350);
DISPLAY BOTH (3550 2350);
FORCEPROP 0 LAST GROUP PWR_MLCC_CAP
J 0
(3556 2237);
DISPLAY 0.638298 (3556 2237);
PAINT BROWN (3556 2237);
DISPLAY BOTH (3556 2237);
FORCEPROP 0 LAST BOM_SS NOPOP
J 0
(3550 2300);
DISPLAY 0.638298 (3550 2300);
PAINT BROWN (3550 2300);
DISPLAY BOTH (3550 2300);
FORCEPROP 1 LAST LOCATION C5L2
J 0
(3550 2925);
DISPLAY 0.617021 (3550 2925);
PAINT AQUA (3550 2925);
FORCEPROP 2 LAST CDS_LIB mstr_discrete
J 0
(3500 2825);
DISPLAY INVISIBLE (3500 2825);
FORCEPROP 1 LAST PATH I311
J 0
(3550 2975);
DISPLAY 0.978723 (3550 2975);
PAINT WHITE (3550 2975);
DISPLAY INVISIBLE (3550 2975);
FORCEPROP 2 LAST BOM_COST MEM_VRD_PVDDQ_CD
J 0
(3550 2975);
PAINT MONO (3550 2975);
DISPLAY INVISIBLE (3550 2975);
FORCEPROP 2 LAST ROOM VDDQ_ABC_PWR_VR
J 0
(3550 2975);
PAINT MONO (3550 2975);
DISPLAY INVISIBLE (3550 2975);
FORCEPROP 1 LAST MATERIAL X5R
J 0
(3550 2725);
DISPLAY 0.617021 (3550 2725);
PAINT SKYBLUE (3550 2725);
DISPLAY INVISIBLE (3550 2725);
FORCEPROP 1 LASTPIN (3500 2725) $PN 2
J 0
(3510 2705);
DISPLAY 0.787234 (3510 2705);
PAINT ORANGE (3510 2705);
DISPLAY INVISIBLE (3510 2705);
FORCEPROP 1 LASTPIN (3500 2925) $PN 1
J 0
(3510 2905);
DISPLAY 0.787234 (3510 2905);
PAINT ORANGE (3510 2905);
DISPLAY INVISIBLE (3510 2905);
FORCEADD CAP..1
(4250 2825);
FORCEPROP 0 LAST NEW_PN 078.1071T.M002
J 0
(4308 2407);
DISPLAY 0.638298 (4308 2407);
PAINT BROWN (4308 2407);
DISPLAY BOTH (4308 2407);
FORCEPROP 1 LAST PACK_TYPE 0805
J 0
(4300 2675);
DISPLAY 0.617021 (4300 2675);
PAINT SKYBLUE (4300 2675);
FORCEPROP 1 LAST PART_NUMBER 602433-112
J 0
(4300 2725);
DISPLAY 0.617021 (4300 2725);
PAINT BLUE (4300 2725);
FORCEPROP 1 LAST LOCATION C5M12
J 0
(4300 2925);
DISPLAY 0.617021 (4300 2925);
PAINT AQUA (4300 2925);
FORCEPROP 1 LAST VALUE 100UF
J 0
(4300 2875);
DISPLAY 0.617021 (4300 2875);
PAINT SKYBLUE (4300 2875);
FORCEPROP 1 LASTPIN (4250 2925) $PN 1
J 0
(4260 2905);
DISPLAY 0.617021 (4260 2905);
PAINT ORANGE (4260 2905);
FORCEPROP 1 LASTPIN (4250 2725) $PN 2
J 0
(4260 2705);
DISPLAY 0.617021 (4260 2705);
PAINT ORANGE (4260 2705);
FORCEPROP 1 LAST TOLERANCE 20%
J 0
(4300 2775);
DISPLAY 0.617021 (4300 2775);
PAINT SKYBLUE (4300 2775);
FORCEPROP 1 LAST VOLTAGE 4V
J 0
(4300 2825);
DISPLAY 0.617021 (4300 2825);
PAINT SKYBLUE (4300 2825);
FORCEPROP 0 LAST NEW_MATERIAL X6S
J 0
(4300 2350);
DISPLAY 0.638298 (4300 2350);
PAINT BROWN (4300 2350);
DISPLAY BOTH (4300 2350);
FORCEPROP 0 LAST BOM_SS NOPOP
J 0
(4300 2300);
DISPLAY 0.638298 (4300 2300);
PAINT BROWN (4300 2300);
DISPLAY BOTH (4300 2300);
FORCEPROP 0 LAST GROUP PWR_MLCC_CAP
J 0
(4306 2262);
DISPLAY 0.638298 (4306 2262);
PAINT BROWN (4306 2262);
DISPLAY BOTH (4306 2262);
FORCEPROP 0 LAST CDS_SEC 1
J 0
(4300 2975);
PAINT MONO (4300 2975);
DISPLAY INVISIBLE (4300 2975);
FORCEPROP 2 LAST CDS_LIB mstr_discrete
J 0
(4250 2825);
PAINT MONO (4250 2825);
DISPLAY INVISIBLE (4250 2825);
FORCEPROP 2 LAST BOM_COST MEM_VRD_PVDDQ_CD
J 0
(4300 2975);
PAINT MONO (4300 2975);
DISPLAY INVISIBLE (4300 2975);
FORCEPROP 2 LAST ROOM VDDQ_ABC_PWR_VR
J 0
(4300 2975);
PAINT MONO (4300 2975);
DISPLAY INVISIBLE (4300 2975);
FORCEPROP 2 LAST SEC_TYPE 0805
J 0
(4300 3025);
DISPLAY 1.021277 (4300 3025);
PAINT ORANGE (4300 3025);
DISPLAY INVISIBLE (4300 3025);
FORCEPROP 2 LAST SEC 1
J 0
(4300 3025);
DISPLAY 0.680851 (4300 3025);
PAINT MONO (4300 3025);
DISPLAY INVISIBLE (4300 3025);
FORCEPROP 1 LAST MATERIAL X5R
J 0
(4300 2725);
DISPLAY 0.617021 (4300 2725);
PAINT SKYBLUE (4300 2725);
DISPLAY INVISIBLE (4300 2725);
FORCEPROP 1 LAST PATH I312
J 0
(4300 2975);
DISPLAY 0.978723 (4300 2975);
PAINT WHITE (4300 2975);
DISPLAY INVISIBLE (4300 2975);
FORCEPROP 2 LAST CDS_LOCATION C5M12
J 0
(4300 2925);
DISPLAY 0.617021 (4300 2925);
PAINT AQUA (4300 2925);
DISPLAY INVISIBLE (4300 2925);
FORCEADD CAP..1
(4600 2825);
FORCEPROP 0 LAST NEW_PN 078.1071T.M002
J 0
(4654 2631);
DISPLAY 0.638298 (4654 2631);
PAINT BROWN (4654 2631);
DISPLAY BOTH (4654 2631);
FORCEPROP 1 LAST PART_NUMBER 602433-112
J 0
(4650 2725);
DISPLAY 0.617021 (4650 2725);
PAINT BLUE (4650 2725);
FORCEPROP 1 LASTPIN (4600 2725) $PN 2
J 0
(4610 2705);
DISPLAY 0.617021 (4610 2705);
PAINT ORANGE (4610 2705);
FORCEPROP 1 LAST VALUE 100UF
J 0
(4650 2875);
DISPLAY 0.617021 (4650 2875);
PAINT SKYBLUE (4650 2875);
FORCEPROP 1 LASTPIN (4600 2925) $PN 1
J 0
(4610 2905);
DISPLAY 0.617021 (4610 2905);
PAINT ORANGE (4610 2905);
FORCEPROP 1 LAST LOCATION C5L14
J 0
(4650 2925);
DISPLAY 0.617021 (4650 2925);
PAINT AQUA (4650 2925);
FORCEPROP 1 LAST PACK_TYPE 0805
J 0
(4650 2675);
DISPLAY 0.617021 (4650 2675);
PAINT SKYBLUE (4650 2675);
FORCEPROP 1 LAST VOLTAGE 4V
J 0
(4650 2825);
DISPLAY 0.617021 (4650 2825);
PAINT SKYBLUE (4650 2825);
FORCEPROP 1 LAST TOLERANCE 20%
J 0
(4650 2775);
DISPLAY 0.617021 (4650 2775);
PAINT SKYBLUE (4650 2775);
FORCEPROP 0 LAST NEW_MATERIAL X6S
J 0
(4650 2575);
DISPLAY 0.638298 (4650 2575);
PAINT BROWN (4650 2575);
DISPLAY BOTH (4650 2575);
FORCEPROP 0 LAST BOM_SS NOPOP
J 0
(4650 2525);
DISPLAY 0.638298 (4650 2525);
PAINT BROWN (4650 2525);
DISPLAY BOTH (4650 2525);
FORCEPROP 0 LAST GROUP PWR_MLCC_CAP
J 0
(4656 2462);
DISPLAY 0.638298 (4656 2462);
PAINT BROWN (4656 2462);
DISPLAY BOTH (4656 2462);
FORCEPROP 1 LAST PATH I313
J 0
(4650 2975);
DISPLAY 0.978723 (4650 2975);
PAINT WHITE (4650 2975);
DISPLAY INVISIBLE (4650 2975);
FORCEPROP 1 LAST MATERIAL X5R
J 0
(4650 2725);
DISPLAY 0.617021 (4650 2725);
PAINT SKYBLUE (4650 2725);
DISPLAY INVISIBLE (4650 2725);
FORCEPROP 2 LAST SEC 1
J 0
(4650 3025);
DISPLAY 0.680851 (4650 3025);
PAINT MONO (4650 3025);
DISPLAY INVISIBLE (4650 3025);
FORCEPROP 2 LAST SEC_TYPE 0805
J 0
(4650 3025);
DISPLAY 1.021277 (4650 3025);
PAINT ORANGE (4650 3025);
DISPLAY INVISIBLE (4650 3025);
FORCEPROP 2 LAST ROOM VDDQ_ABC_PWR_VR
J 0
(4650 2975);
PAINT MONO (4650 2975);
DISPLAY INVISIBLE (4650 2975);
FORCEPROP 2 LAST BOM_COST MEM_VRD_PVDDQ_CD
J 0
(4650 2975);
PAINT MONO (4650 2975);
DISPLAY INVISIBLE (4650 2975);
FORCEPROP 2 LAST CDS_LIB mstr_discrete
J 0
(4600 2825);
PAINT MONO (4600 2825);
DISPLAY INVISIBLE (4600 2825);
FORCEPROP 0 LAST CDS_SEC 1
J 0
(4650 2975);
PAINT MONO (4650 2975);
DISPLAY INVISIBLE (4650 2975);
FORCEPROP 2 LAST CDS_LOCATION C5L14
J 0
(4650 2925);
DISPLAY 0.617021 (4650 2925);
PAINT AQUA (4650 2925);
DISPLAY INVISIBLE (4650 2925);
FORCEADD CAP..1
(5000 2825);
FORCEPROP 0 LAST NEW_PN 078.1071T.M002
J 0
(5048 2394);
DISPLAY 0.638298 (5048 2394);
PAINT BROWN (5048 2394);
DISPLAY BOTH (5048 2394);
FORCEPROP 1 LASTPIN (5000 2725) $PN 2
J 0
(5010 2705);
DISPLAY 0.617021 (5010 2705);
PAINT ORANGE (5010 2705);
FORCEPROP 1 LAST PACK_TYPE 0805
J 0
(5050 2675);
DISPLAY 0.617021 (5050 2675);
PAINT SKYBLUE (5050 2675);
FORCEPROP 1 LAST LOCATION C5M8
J 0
(5050 2925);
DISPLAY 0.617021 (5050 2925);
PAINT AQUA (5050 2925);
FORCEPROP 1 LASTPIN (5000 2925) $PN 1
J 0
(5010 2905);
DISPLAY 0.617021 (5010 2905);
PAINT ORANGE (5010 2905);
FORCEPROP 1 LAST VOLTAGE 4V
J 0
(5050 2825);
DISPLAY 0.617021 (5050 2825);
PAINT SKYBLUE (5050 2825);
FORCEPROP 1 LAST PART_NUMBER 602433-112
J 0
(5050 2725);
DISPLAY 0.617021 (5050 2725);
PAINT BLUE (5050 2725);
FORCEPROP 0 LAST BOM_SS NOPOP
J 0
(5050 2300);
DISPLAY 0.638298 (5050 2300);
PAINT BROWN (5050 2300);
DISPLAY BOTH (5050 2300);
FORCEPROP 0 LAST GROUP PWR_MLCC_CAP
J 0
(5056 2262);
DISPLAY 0.638298 (5056 2262);
PAINT BROWN (5056 2262);
DISPLAY BOTH (5056 2262);
FORCEPROP 0 LAST NEW_MATERIAL X6S
J 0
(5050 2350);
DISPLAY 0.638298 (5050 2350);
PAINT BROWN (5050 2350);
DISPLAY BOTH (5050 2350);
FORCEPROP 1 LAST VALUE 100UF
J 0
(5050 2875);
DISPLAY 0.617021 (5050 2875);
PAINT SKYBLUE (5050 2875);
FORCEPROP 1 LAST TOLERANCE 20%
J 0
(5050 2775);
DISPLAY 0.617021 (5050 2775);
PAINT SKYBLUE (5050 2775);
FORCEPROP 1 LAST PATH I314
J 0
(5050 2975);
DISPLAY 0.978723 (5050 2975);
PAINT WHITE (5050 2975);
DISPLAY INVISIBLE (5050 2975);
FORCEPROP 0 LAST CDS_SEC 1
J 0
(5050 2975);
PAINT MONO (5050 2975);
DISPLAY INVISIBLE (5050 2975);
FORCEPROP 2 LAST CDS_LIB mstr_discrete
J 0
(5000 2825);
PAINT MONO (5000 2825);
DISPLAY INVISIBLE (5000 2825);
FORCEPROP 2 LAST BOM_COST MEM_VRD_PVDDQ_CD
J 0
(5050 2975);
PAINT MONO (5050 2975);
DISPLAY INVISIBLE (5050 2975);
FORCEPROP 2 LAST ROOM VDDQ_ABC_PWR_VR
J 0
(5050 2975);
PAINT MONO (5050 2975);
DISPLAY INVISIBLE (5050 2975);
FORCEPROP 2 LAST SEC_TYPE 0805
J 0
(5050 3025);
DISPLAY 1.021277 (5050 3025);
PAINT ORANGE (5050 3025);
DISPLAY INVISIBLE (5050 3025);
FORCEPROP 2 LAST SEC 1
J 0
(5050 3025);
DISPLAY 0.680851 (5050 3025);
PAINT MONO (5050 3025);
DISPLAY INVISIBLE (5050 3025);
FORCEPROP 1 LAST MATERIAL X5R
J 0
(5050 2725);
DISPLAY 0.617021 (5050 2725);
PAINT SKYBLUE (5050 2725);
DISPLAY INVISIBLE (5050 2725);
FORCEPROP 2 LAST CDS_LOCATION C5M8
J 0
(5050 2925);
DISPLAY 0.617021 (5050 2925);
PAINT AQUA (5050 2925);
DISPLAY INVISIBLE (5050 2925);
FORCEADD CAP..1
(1600 2950);
FORCEPROP 1 LAST LOCATION C5P3
J 0
(1650 3050);
DISPLAY 0.617021 (1650 3050);
PAINT AQUA (1650 3050);
FORCEPROP 1 LAST PART_NUMBER 602433-112
J 0
(1650 2850);
DISPLAY 0.617021 (1650 2850);
PAINT BLUE (1650 2850);
FORCEPROP 0 LAST NEW_MATERIAL X6S
J 0
(1650 2700);
DISPLAY 0.638298 (1650 2700);
PAINT BROWN (1650 2700);
DISPLAY BOTH (1650 2700);
FORCEPROP 0 LAST BOM_SS NOPOP
J 0
(1650 2625);
DISPLAY 0.638298 (1650 2625);
PAINT BROWN (1650 2625);
DISPLAY BOTH (1650 2625);
FORCEPROP 1 LAST TOLERANCE 20%
J 0
(1650 2900);
DISPLAY 0.617021 (1650 2900);
PAINT SKYBLUE (1650 2900);
FORCEPROP 1 LAST PACK_TYPE 0805
J 0
(1650 2800);
DISPLAY 0.617021 (1650 2800);
PAINT SKYBLUE (1650 2800);
FORCEPROP 1 LAST VALUE 100UF
J 0
(1650 3000);
DISPLAY 0.617021 (1650 3000);
PAINT SKYBLUE (1650 3000);
FORCEPROP 1 LASTPIN (1600 3050) $PN 1
J 0
(1610 3030);
DISPLAY 0.617021 (1610 3030);
PAINT ORANGE (1610 3030);
FORCEPROP 1 LASTPIN (1600 2850) $PN 2
J 0
(1610 2830);
DISPLAY 0.617021 (1610 2830);
PAINT ORANGE (1610 2830);
FORCEPROP 1 LAST VOLTAGE 4V
J 0
(1650 2950);
DISPLAY 0.617021 (1650 2950);
PAINT SKYBLUE (1650 2950);
FORCEPROP 0 LAST GROUP PWR_MLCC_CAP
J 0
(1656 2662);
DISPLAY 0.638298 (1656 2662);
PAINT BROWN (1656 2662);
DISPLAY BOTH (1656 2662);
FORCEPROP 0 LAST NEW_PN 078.1071T.M002
J 0
(1655 2743);
DISPLAY 0.638298 (1655 2743);
PAINT BROWN (1655 2743);
DISPLAY BOTH (1655 2743);
FORCEPROP 0 LAST CDS_SEC 1
J 0
(1650 3100);
PAINT MONO (1650 3100);
DISPLAY INVISIBLE (1650 3100);
FORCEPROP 2 LAST CDS_LIB mstr_discrete
J 0
(1600 2950);
PAINT MONO (1600 2950);
DISPLAY INVISIBLE (1600 2950);
FORCEPROP 2 LAST BOM_COST MEM_VRD_PVDDQ_CD
J 0
(1650 3100);
PAINT MONO (1650 3100);
DISPLAY INVISIBLE (1650 3100);
FORCEPROP 2 LAST ROOM VDDQ_ABC_PWR_VR
J 0
(1650 3100);
PAINT MONO (1650 3100);
DISPLAY INVISIBLE (1650 3100);
FORCEPROP 2 LAST SEC_TYPE 0805
J 0
(1650 3150);
DISPLAY 1.021277 (1650 3150);
PAINT ORANGE (1650 3150);
DISPLAY INVISIBLE (1650 3150);
FORCEPROP 2 LAST SEC 1
J 0
(1650 3150);
DISPLAY 0.680851 (1650 3150);
PAINT MONO (1650 3150);
DISPLAY INVISIBLE (1650 3150);
FORCEPROP 1 LAST MATERIAL X5R
J 0
(1650 2850);
DISPLAY 0.617021 (1650 2850);
PAINT SKYBLUE (1650 2850);
DISPLAY INVISIBLE (1650 2850);
FORCEPROP 1 LAST PATH I315
J 0
(1650 3100);
DISPLAY 0.978723 (1650 3100);
PAINT WHITE (1650 3100);
DISPLAY INVISIBLE (1650 3100);
FORCEPROP 2 LAST CDS_LOCATION C5P3
J 0
(1650 3050);
DISPLAY 0.617021 (1650 3050);
PAINT AQUA (1650 3050);
DISPLAY INVISIBLE (1650 3050);
FORCEADD CAP..1
(175 2925);
FORCEPROP 0 LAST NEW_PN 078.1071T.M002
J 0
(226 2736);
DISPLAY 0.638298 (226 2736);
PAINT BROWN (226 2736);
DISPLAY BOTH (226 2736);
FORCEPROP 1 LAST VALUE 100UF
J 0
(225 2975);
DISPLAY 0.617021 (225 2975);
PAINT SKYBLUE (225 2975);
FORCEPROP 1 LAST LOCATION C5P6
J 0
(225 3025);
DISPLAY 0.617021 (225 3025);
PAINT AQUA (225 3025);
FORCEPROP 1 LASTPIN (175 3025) $PN 1
J 0
(185 3005);
DISPLAY 0.617021 (185 3005);
PAINT ORANGE (185 3005);
FORCEPROP 1 LAST PACK_TYPE 0805
J 0
(225 2775);
DISPLAY 0.617021 (225 2775);
PAINT SKYBLUE (225 2775);
FORCEPROP 1 LAST PART_NUMBER 602433-112
J 0
(225 2825);
DISPLAY 0.617021 (225 2825);
PAINT BLUE (225 2825);
FORCEPROP 1 LAST TOLERANCE 20%
J 0
(225 2875);
DISPLAY 0.617021 (225 2875);
PAINT SKYBLUE (225 2875);
FORCEPROP 1 LAST VOLTAGE 4V
J 0
(225 2925);
DISPLAY 0.617021 (225 2925);
PAINT SKYBLUE (225 2925);
FORCEPROP 0 LAST NEW_MATERIAL X6S
J 0
(225 2675);
DISPLAY 0.638298 (225 2675);
PAINT BROWN (225 2675);
DISPLAY BOTH (225 2675);
FORCEPROP 0 LAST BOM_SS NOPOP
J 0
(200 2550);
DISPLAY 0.638298 (200 2550);
PAINT BROWN (200 2550);
DISPLAY BOTH (200 2550);
FORCEPROP 1 LASTPIN (175 2825) $PN 2
J 0
(185 2805);
DISPLAY 0.617021 (185 2805);
PAINT ORANGE (185 2805);
FORCEPROP 0 LAST GROUP PWR_MLCC_CAP
J 0
(231 2637);
DISPLAY 0.638298 (231 2637);
PAINT BROWN (231 2637);
DISPLAY BOTH (231 2637);
FORCEPROP 1 LAST MATERIAL X5R
J 0
(225 2825);
DISPLAY 0.617021 (225 2825);
PAINT SKYBLUE (225 2825);
DISPLAY INVISIBLE (225 2825);
FORCEPROP 2 LAST SEC 1
J 0
(225 3125);
DISPLAY 0.680851 (225 3125);
PAINT MONO (225 3125);
DISPLAY INVISIBLE (225 3125);
FORCEPROP 2 LAST SEC_TYPE 0805
J 0
(225 3125);
DISPLAY 1.021277 (225 3125);
PAINT ORANGE (225 3125);
DISPLAY INVISIBLE (225 3125);
FORCEPROP 2 LAST ROOM VDDQ_ABC_PWR_VR
J 0
(225 3075);
PAINT MONO (225 3075);
DISPLAY INVISIBLE (225 3075);
FORCEPROP 2 LAST BOM_COST MEM_VRD_PVDDQ_CD
J 0
(225 3075);
PAINT MONO (225 3075);
DISPLAY INVISIBLE (225 3075);
FORCEPROP 2 LAST CDS_LIB mstr_discrete
J 0
(175 2925);
PAINT MONO (175 2925);
DISPLAY INVISIBLE (175 2925);
FORCEPROP 0 LAST CDS_SEC 1
J 0
(225 3075);
PAINT MONO (225 3075);
DISPLAY INVISIBLE (225 3075);
FORCEPROP 1 LAST PATH I316
J 0
(225 3075);
DISPLAY 0.978723 (225 3075);
PAINT WHITE (225 3075);
DISPLAY INVISIBLE (225 3075);
FORCEPROP 2 LAST CDS_LOCATION C5P6
J 0
(225 3025);
DISPLAY 0.617021 (225 3025);
PAINT AQUA (225 3025);
DISPLAY INVISIBLE (225 3025);
FORCEADD CAP..1
(500 2925);
FORCEPROP 1 LAST VALUE 100UF
J 0
(550 2975);
DISPLAY 0.617021 (550 2975);
PAINT SKYBLUE (550 2975);
FORCEPROP 1 LAST VOLTAGE 4V
J 0
(550 2925);
DISPLAY 0.617021 (550 2925);
PAINT SKYBLUE (550 2925);
FORCEPROP 1 LAST TOLERANCE 20%
J 0
(550 2875);
DISPLAY 0.617021 (550 2875);
PAINT SKYBLUE (550 2875);
FORCEPROP 1 LAST PART_NUMBER 602433-112
J 0
(550 2825);
DISPLAY 0.617021 (550 2825);
PAINT BLUE (550 2825);
FORCEPROP 1 LASTPIN (500 2825) $PN 2
J 0
(510 2805);
DISPLAY 0.617021 (510 2805);
PAINT ORANGE (510 2805);
FORCEPROP 0 LAST BOM_SS NOPOP
J 0
(525 3100);
DISPLAY 0.638298 (525 3100);
PAINT BROWN (525 3100);
DISPLAY BOTH (525 3100);
FORCEPROP 1 LAST PACK_TYPE 0805
J 0
(550 2775);
DISPLAY 0.617021 (550 2775);
PAINT SKYBLUE (550 2775);
FORCEPROP 1 LAST LOCATION C5P5
J 0
(550 3025);
DISPLAY 0.617021 (550 3025);
PAINT AQUA (550 3025);
FORCEPROP 1 LASTPIN (500 3025) $PN 1
J 0
(510 3005);
DISPLAY 0.617021 (510 3005);
PAINT ORANGE (510 3005);
FORCEPROP 0 LAST GROUP PWR_MLCC_CAP
J 0
(556 2512);
DISPLAY 0.638298 (556 2512);
PAINT BROWN (556 2512);
DISPLAY BOTH (556 2512);
FORCEPROP 0 LAST NEW_MATERIAL X6S
J 0
(550 2550);
DISPLAY 0.638298 (550 2550);
PAINT BROWN (550 2550);
DISPLAY BOTH (550 2550);
FORCEPROP 0 LAST NEW_PN 078.1071T.M002
J 0
(552 2603);
DISPLAY 0.638298 (552 2603);
PAINT BROWN (552 2603);
DISPLAY BOTH (552 2603);
FORCEPROP 1 LAST PATH I317
J 0
(550 3075);
DISPLAY 0.978723 (550 3075);
PAINT WHITE (550 3075);
DISPLAY INVISIBLE (550 3075);
FORCEPROP 1 LAST MATERIAL X5R
J 0
(550 2825);
DISPLAY 0.617021 (550 2825);
PAINT SKYBLUE (550 2825);
DISPLAY INVISIBLE (550 2825);
FORCEPROP 2 LAST SEC 1
J 0
(550 3125);
DISPLAY 0.680851 (550 3125);
PAINT MONO (550 3125);
DISPLAY INVISIBLE (550 3125);
FORCEPROP 2 LAST SEC_TYPE 0805
J 0
(550 3125);
DISPLAY 1.021277 (550 3125);
PAINT ORANGE (550 3125);
DISPLAY INVISIBLE (550 3125);
FORCEPROP 2 LAST ROOM VDDQ_ABC_PWR_VR
J 0
(550 3075);
PAINT MONO (550 3075);
DISPLAY INVISIBLE (550 3075);
FORCEPROP 2 LAST BOM_COST MEM_VRD_PVDDQ_CD
J 0
(550 3075);
PAINT MONO (550 3075);
DISPLAY INVISIBLE (550 3075);
FORCEPROP 2 LAST CDS_LIB mstr_discrete
J 0
(500 2925);
PAINT MONO (500 2925);
DISPLAY INVISIBLE (500 2925);
FORCEPROP 0 LAST CDS_SEC 1
J 0
(550 3075);
PAINT MONO (550 3075);
DISPLAY INVISIBLE (550 3075);
FORCEPROP 2 LAST CDS_LOCATION C5P5
J 0
(550 3025);
DISPLAY 0.617021 (550 3025);
PAINT AQUA (550 3025);
DISPLAY INVISIBLE (550 3025);
FORCEADD CAP..1
(800 2925);
FORCEPROP 1 LAST VALUE 100UF
J 0
(850 2975);
DISPLAY 0.617021 (850 2975);
PAINT SKYBLUE (850 2975);
FORCEPROP 1 LAST TOLERANCE 20%
J 0
(850 2875);
DISPLAY 0.617021 (850 2875);
PAINT SKYBLUE (850 2875);
FORCEPROP 1 LAST PACK_TYPE 0805
J 0
(850 2775);
DISPLAY 0.617021 (850 2775);
PAINT SKYBLUE (850 2775);
FORCEPROP 1 LAST LOCATION C5P4
J 0
(850 3025);
DISPLAY 0.617021 (850 3025);
PAINT AQUA (850 3025);
FORCEPROP 1 LASTPIN (800 3025) $PN 1
J 0
(810 3005);
DISPLAY 0.617021 (810 3005);
PAINT ORANGE (810 3005);
FORCEPROP 1 LAST VOLTAGE 4V
J 0
(850 2925);
DISPLAY 0.617021 (850 2925);
PAINT SKYBLUE (850 2925);
FORCEPROP 1 LASTPIN (800 2825) $PN 2
J 0
(810 2805);
DISPLAY 0.617021 (810 2805);
PAINT ORANGE (810 2805);
FORCEPROP 0 LAST GROUP PWR_MLCC_CAP
J 0
(856 2637);
DISPLAY 0.638298 (856 2637);
PAINT BROWN (856 2637);
DISPLAY BOTH (856 2637);
FORCEPROP 0 LAST NEW_MATERIAL X6S
J 0
(850 2675);
DISPLAY 0.638298 (850 2675);
PAINT BROWN (850 2675);
DISPLAY BOTH (850 2675);
FORCEPROP 1 LAST PART_NUMBER 602433-112
J 0
(850 2825);
DISPLAY 0.617021 (850 2825);
PAINT BLUE (850 2825);
FORCEPROP 0 LAST BOM_SS NOPOP
J 0
(875 3100);
DISPLAY 0.638298 (875 3100);
PAINT BROWN (875 3100);
DISPLAY BOTH (875 3100);
FORCEPROP 0 LAST NEW_PN 078.1071T.M002
J 0
(855 2718);
DISPLAY 0.638298 (855 2718);
PAINT BROWN (855 2718);
DISPLAY BOTH (855 2718);
FORCEPROP 1 LAST PATH I318
J 0
(850 3075);
DISPLAY 0.978723 (850 3075);
PAINT WHITE (850 3075);
DISPLAY INVISIBLE (850 3075);
FORCEPROP 1 LAST MATERIAL X5R
J 0
(850 2825);
DISPLAY 0.617021 (850 2825);
PAINT SKYBLUE (850 2825);
DISPLAY INVISIBLE (850 2825);
FORCEPROP 2 LAST SEC 1
J 0
(850 3125);
DISPLAY 0.680851 (850 3125);
PAINT MONO (850 3125);
DISPLAY INVISIBLE (850 3125);
FORCEPROP 2 LAST SEC_TYPE 0805
J 0
(850 3125);
DISPLAY 1.021277 (850 3125);
PAINT ORANGE (850 3125);
DISPLAY INVISIBLE (850 3125);
FORCEPROP 2 LAST ROOM VDDQ_ABC_PWR_VR
J 0
(850 3075);
PAINT MONO (850 3075);
DISPLAY INVISIBLE (850 3075);
FORCEPROP 2 LAST BOM_COST MEM_VRD_PVDDQ_CD
J 0
(850 3075);
PAINT MONO (850 3075);
DISPLAY INVISIBLE (850 3075);
FORCEPROP 2 LAST CDS_LIB mstr_discrete
J 0
(800 2925);
PAINT MONO (800 2925);
DISPLAY INVISIBLE (800 2925);
FORCEPROP 0 LAST CDS_SEC 1
J 0
(850 3075);
PAINT MONO (850 3075);
DISPLAY INVISIBLE (850 3075);
FORCEPROP 2 LAST CDS_LOCATION C5P4
J 0
(850 3025);
DISPLAY 0.617021 (850 3025);
PAINT AQUA (850 3025);
DISPLAY INVISIBLE (850 3025);
FORCEADD CAP..1
(-2300 2975);
FORCEPROP 0 LAST NEW_PN 078.1071T.M002
J 0
(-2244 2770);
DISPLAY 0.638298 (-2244 2770);
PAINT BROWN (-2244 2770);
DISPLAY BOTH (-2244 2770);
FORCEPROP 0 LAST NEW_MATERIAL X6S
J 0
(-2250 2725);
DISPLAY 0.638298 (-2250 2725);
PAINT BROWN (-2250 2725);
DISPLAY BOTH (-2250 2725);
FORCEPROP 0 LAST GROUP PWR_MLCC_CAP
J 0
(-2244 2687);
DISPLAY 0.638298 (-2244 2687);
PAINT BROWN (-2244 2687);
DISPLAY BOTH (-2244 2687);
FORCEPROP 0 LAST BOM_SS NOPOP
J 0
(-2275 2625);
DISPLAY 0.638298 (-2275 2625);
PAINT BROWN (-2275 2625);
DISPLAY BOTH (-2275 2625);
FORCEPROP 1 LASTPIN (-2300 3075) $PN 1
J 0
(-2290 3055);
DISPLAY 0.617021 (-2290 3055);
PAINT ORANGE (-2290 3055);
FORCEPROP 1 LASTPIN (-2300 2875) $PN 2
J 0
(-2290 2855);
DISPLAY 0.617021 (-2290 2855);
PAINT ORANGE (-2290 2855);
FORCEPROP 1 LAST TOLERANCE 20%
J 0
(-2250 2925);
DISPLAY 0.617021 (-2250 2925);
PAINT SKYBLUE (-2250 2925);
FORCEPROP 1 LAST VOLTAGE 4V
J 0
(-2250 2975);
DISPLAY 0.617021 (-2250 2975);
PAINT SKYBLUE (-2250 2975);
FORCEPROP 1 LAST VALUE 100UF
J 0
(-2250 3025);
DISPLAY 0.617021 (-2250 3025);
PAINT SKYBLUE (-2250 3025);
FORCEPROP 1 LAST PART_NUMBER 602433-112
J 0
(-2250 2875);
DISPLAY 0.617021 (-2250 2875);
PAINT BLUE (-2250 2875);
FORCEPROP 1 LAST PACK_TYPE 0805
J 0
(-2250 2825);
DISPLAY 0.617021 (-2250 2825);
PAINT SKYBLUE (-2250 2825);
FORCEPROP 1 LAST LOCATION C5P2
J 0
(-2250 3075);
DISPLAY 0.617021 (-2250 3075);
PAINT AQUA (-2250 3075);
FORCEPROP 0 LAST CDS_SEC 1
J 0
(-2250 3125);
PAINT MONO (-2250 3125);
DISPLAY INVISIBLE (-2250 3125);
FORCEPROP 2 LAST CDS_LIB mstr_discrete
J 0
(-2300 2975);
PAINT MONO (-2300 2975);
DISPLAY INVISIBLE (-2300 2975);
FORCEPROP 2 LAST BOM_COST MEM_VRD_PVDDQ_CD
J 0
(-2250 3125);
PAINT MONO (-2250 3125);
DISPLAY INVISIBLE (-2250 3125);
FORCEPROP 2 LAST ROOM VDDQ_ABC_PWR_VR
J 0
(-2250 3125);
PAINT MONO (-2250 3125);
DISPLAY INVISIBLE (-2250 3125);
FORCEPROP 2 LAST SEC_TYPE 0805
J 0
(-2250 3175);
DISPLAY 1.021277 (-2250 3175);
PAINT ORANGE (-2250 3175);
DISPLAY INVISIBLE (-2250 3175);
FORCEPROP 2 LAST SEC 1
J 0
(-2250 3175);
DISPLAY 0.680851 (-2250 3175);
PAINT MONO (-2250 3175);
DISPLAY INVISIBLE (-2250 3175);
FORCEPROP 1 LAST MATERIAL X5R
J 0
(-2250 2875);
DISPLAY 0.617021 (-2250 2875);
PAINT SKYBLUE (-2250 2875);
DISPLAY INVISIBLE (-2250 2875);
FORCEPROP 1 LAST PATH I319
J 0
(-2250 3125);
DISPLAY 0.978723 (-2250 3125);
PAINT WHITE (-2250 3125);
DISPLAY INVISIBLE (-2250 3125);
FORCEPROP 2 LAST CDS_LOCATION C5P2
J 0
(-2250 3075);
DISPLAY 0.617021 (-2250 3075);
PAINT AQUA (-2250 3075);
DISPLAY INVISIBLE (-2250 3075);
FORCEADD CAP..1
(-1950 2975);
FORCEPROP 0 LAST NEW_PN 078.1071T.M002
J 0
(-1888 2664);
DISPLAY 0.638298 (-1888 2664);
PAINT BROWN (-1888 2664);
DISPLAY BOTH (-1888 2664);
FORCEPROP 1 LAST LOCATION C5P1
J 0
(-1900 3075);
DISPLAY 0.617021 (-1900 3075);
PAINT AQUA (-1900 3075);
FORCEPROP 0 LAST GROUP PWR_MLCC_CAP
J 0
(-1894 2587);
DISPLAY 0.638298 (-1894 2587);
PAINT BROWN (-1894 2587);
DISPLAY BOTH (-1894 2587);
FORCEPROP 0 LAST NEW_MATERIAL X6S
J 0
(-1900 2625);
DISPLAY 0.638298 (-1900 2625);
PAINT BROWN (-1900 2625);
DISPLAY BOTH (-1900 2625);
FORCEPROP 0 LAST BOM_SS NOPOP
J 0
(-1900 2525);
DISPLAY 0.638298 (-1900 2525);
PAINT BROWN (-1900 2525);
DISPLAY BOTH (-1900 2525);
FORCEPROP 1 LAST VALUE 100UF
J 0
(-1900 3025);
DISPLAY 0.617021 (-1900 3025);
PAINT SKYBLUE (-1900 3025);
FORCEPROP 1 LAST PART_NUMBER 602433-112
J 0
(-1900 2875);
DISPLAY 0.617021 (-1900 2875);
PAINT BLUE (-1900 2875);
FORCEPROP 1 LAST VOLTAGE 4V
J 0
(-1900 2975);
DISPLAY 0.617021 (-1900 2975);
PAINT SKYBLUE (-1900 2975);
FORCEPROP 1 LAST TOLERANCE 20%
J 0
(-1900 2925);
DISPLAY 0.617021 (-1900 2925);
PAINT SKYBLUE (-1900 2925);
FORCEPROP 1 LAST PACK_TYPE 0805
J 0
(-1900 2825);
DISPLAY 0.617021 (-1900 2825);
PAINT SKYBLUE (-1900 2825);
FORCEPROP 1 LASTPIN (-1950 2875) $PN 2
J 0
(-1940 2855);
DISPLAY 0.617021 (-1940 2855);
PAINT ORANGE (-1940 2855);
FORCEPROP 1 LASTPIN (-1950 3075) $PN 1
J 0
(-1940 3055);
DISPLAY 0.617021 (-1940 3055);
PAINT ORANGE (-1940 3055);
FORCEPROP 1 LAST PATH I320
J 0
(-1900 3125);
DISPLAY 0.978723 (-1900 3125);
PAINT WHITE (-1900 3125);
DISPLAY INVISIBLE (-1900 3125);
FORCEPROP 0 LAST CDS_SEC 1
J 0
(-1900 3125);
PAINT MONO (-1900 3125);
DISPLAY INVISIBLE (-1900 3125);
FORCEPROP 2 LAST CDS_LIB mstr_discrete
J 0
(-1950 2975);
PAINT MONO (-1950 2975);
DISPLAY INVISIBLE (-1950 2975);
FORCEPROP 2 LAST BOM_COST MEM_VRD_PVDDQ_CD
J 0
(-1900 3125);
PAINT MONO (-1900 3125);
DISPLAY INVISIBLE (-1900 3125);
FORCEPROP 2 LAST ROOM VDDQ_ABC_PWR_VR
J 0
(-1900 3125);
PAINT MONO (-1900 3125);
DISPLAY INVISIBLE (-1900 3125);
FORCEPROP 2 LAST SEC_TYPE 0805
J 0
(-1900 3175);
DISPLAY 1.021277 (-1900 3175);
PAINT ORANGE (-1900 3175);
DISPLAY INVISIBLE (-1900 3175);
FORCEPROP 2 LAST SEC 1
J 0
(-1900 3175);
DISPLAY 0.680851 (-1900 3175);
PAINT MONO (-1900 3175);
DISPLAY INVISIBLE (-1900 3175);
FORCEPROP 1 LAST MATERIAL X5R
J 0
(-1900 2875);
DISPLAY 0.617021 (-1900 2875);
PAINT SKYBLUE (-1900 2875);
DISPLAY INVISIBLE (-1900 2875);
FORCEPROP 2 LAST CDS_LOCATION C5P1
J 0
(-1900 3075);
DISPLAY 0.617021 (-1900 3075);
PAINT AQUA (-1900 3075);
DISPLAY INVISIBLE (-1900 3075);
FORCEADD CAP..1
(2400 2825);
FORCEPROP 0 LAST NEW_PN 078.1071T.M002
J 0
(2453 2621);
DISPLAY 0.638298 (2453 2621);
PAINT BROWN (2453 2621);
DISPLAY BOTH (2453 2621);
FORCEPROP 1 LAST VOLTAGE 4V
J 0
(2450 2825);
DISPLAY 0.617021 (2450 2825);
PAINT SKYBLUE (2450 2825);
FORCEPROP 1 LASTPIN (2400 2925) $PN 1
J 0
(2410 2905);
DISPLAY 0.617021 (2410 2905);
PAINT ORANGE (2410 2905);
FORCEPROP 1 LAST PACK_TYPE 0805
J 0
(2450 2675);
DISPLAY 0.617021 (2450 2675);
PAINT SKYBLUE (2450 2675);
FORCEPROP 1 LAST TOLERANCE 20%
J 0
(2450 2775);
DISPLAY 0.617021 (2450 2775);
PAINT SKYBLUE (2450 2775);
FORCEPROP 1 LASTPIN (2400 2725) $PN 2
J 0
(2410 2705);
DISPLAY 0.617021 (2410 2705);
PAINT ORANGE (2410 2705);
FORCEPROP 0 LAST NEW_MATERIAL X6S
J 0
(2450 2575);
DISPLAY 0.638298 (2450 2575);
PAINT BROWN (2450 2575);
DISPLAY BOTH (2450 2575);
FORCEPROP 0 LAST BOM_SS NOPOP
J 0
(2450 2525);
DISPLAY 0.638298 (2450 2525);
PAINT BROWN (2450 2525);
DISPLAY BOTH (2450 2525);
FORCEPROP 0 LAST GROUP PWR_MLCC_CAP
J 0
(2456 2487);
DISPLAY 0.638298 (2456 2487);
PAINT BROWN (2456 2487);
DISPLAY BOTH (2456 2487);
FORCEPROP 1 LAST PART_NUMBER 602433-112
J 0
(2450 2725);
DISPLAY 0.617021 (2450 2725);
PAINT BLUE (2450 2725);
FORCEPROP 1 LAST VALUE 100UF
J 0
(2450 2875);
DISPLAY 0.617021 (2450 2875);
PAINT SKYBLUE (2450 2875);
FORCEPROP 1 LAST LOCATION C5A10
J 0
(2450 2925);
DISPLAY 0.617021 (2450 2925);
PAINT AQUA (2450 2925);
FORCEPROP 1 LAST MATERIAL X5R
J 0
(2450 2725);
DISPLAY 0.617021 (2450 2725);
PAINT SKYBLUE (2450 2725);
DISPLAY INVISIBLE (2450 2725);
FORCEPROP 2 LAST SEC 1
J 0
(2450 3025);
DISPLAY 0.680851 (2450 3025);
PAINT MONO (2450 3025);
DISPLAY INVISIBLE (2450 3025);
FORCEPROP 2 LAST SEC_TYPE 0805
J 0
(2450 3025);
DISPLAY 1.021277 (2450 3025);
PAINT ORANGE (2450 3025);
DISPLAY INVISIBLE (2450 3025);
FORCEPROP 2 LAST ROOM VDDQ_ABC_PWR_VR
J 0
(2450 2975);
PAINT MONO (2450 2975);
DISPLAY INVISIBLE (2450 2975);
FORCEPROP 2 LAST BOM_COST MEM_VRD_PVDDQ_CD
J 0
(2450 2975);
PAINT MONO (2450 2975);
DISPLAY INVISIBLE (2450 2975);
FORCEPROP 2 LAST CDS_LIB mstr_discrete
J 0
(2400 2825);
PAINT MONO (2400 2825);
DISPLAY INVISIBLE (2400 2825);
FORCEPROP 0 LAST CDS_SEC 1
J 0
(2450 2975);
PAINT MONO (2450 2975);
DISPLAY INVISIBLE (2450 2975);
FORCEPROP 1 LAST PATH I321
J 0
(2450 2975);
DISPLAY 0.978723 (2450 2975);
PAINT WHITE (2450 2975);
DISPLAY INVISIBLE (2450 2975);
FORCEPROP 2 LAST CDS_LOCATION C5A10
J 0
(2450 2925);
DISPLAY 0.617021 (2450 2925);
PAINT AQUA (2450 2925);
DISPLAY INVISIBLE (2450 2925);
FORCEADD SE100U16VM-48-GP..1
(-1450 1025);
FORCEPROP 0 LAST RATED 16V
J 0
(-1400 975);
DISPLAY 0.638298 (-1400 975);
PAINT GREEN (-1400 975);
FORCEPROP 0 LAST ATTRIBUTE 100UF
J 0
(-1400 1025);
DISPLAY 0.638298 (-1400 1025);
PAINT GREEN (-1400 1025);
FORCEPROP 2 LASTPIN (-1450 1100) $PN 1
R 1
J 0
(-1460 1110);
DISPLAY 0.808511 (-1460 1110);
PAINT ORANGE (-1460 1110);
FORCEPROP 1 LAST VALUE SE100U16VM-48-GP
J 0
(-1400 925);
DISPLAY 0.617021 (-1400 925);
PAINT GREEN (-1400 925);
FORCEPROP 2 LASTPIN (-1450 950) $PN 2
R 1
J 2
(-1460 940);
DISPLAY 0.808511 (-1460 940);
PAINT ORANGE (-1460 940);
FORCEPROP 1 LAST LOCATION C7W2
J 0
(-1400 1080);
DISPLAY 0.617021 (-1400 1080);
PAINT GREEN (-1400 1080);
FORCEPROP 1 LAST PACK_TYPE SMD-TCG2
J 0
(-1450 1025);
DISPLAY 0.617021 (-1450 1025);
PAINT GREEN (-1450 1025);
DISPLAY INVISIBLE (-1450 1025);
FORCEPROP 2 LAST SEC 1
J 0
(-1425 1100);
DISPLAY 0.680851 (-1425 1100);
PAINT MONO (-1425 1100);
DISPLAY INVISIBLE (-1425 1100);
FORCEPROP 2 LAST SEC_TYPE SMD-TCG2
J 0
(-1425 1100);
DISPLAY 1.021277 (-1425 1100);
PAINT ORANGE (-1425 1100);
DISPLAY INVISIBLE (-1425 1100);
FORCEPROP 1 LAST PART_NUMBER 077.51081.0011
J 0
(-1450 985);
DISPLAY 0.617021 (-1450 985);
PAINT GREEN (-1450 985);
DISPLAY INVISIBLE (-1450 985);
FORCEPROP 2 LAST CDS_LIB w_hdl
J 0
(-1450 1025);
DISPLAY INVISIBLE (-1450 1025);
FORCEPROP 1 LAST PATH I324
J 0
(-1450 1065);
DISPLAY 0.617021 (-1450 1065);
PAINT GREEN (-1450 1065);
DISPLAY INVISIBLE (-1450 1065);
FORCEPROP 1 LAST CDS_LMAN_SYM_OUTLINE -50,25,50,-25
J 0
(-1450 1025);
DISPLAY 0.468085 (-1450 1025);
PAINT GREEN (-1450 1025);
DISPLAY INVISIBLE (-1450 1025);
FORCEADD RES..2
(4100 -100);
FORCEPROP 1 LAST WATTAGE 1/10W
J 0
(4140 -100);
DISPLAY 0.617021 (4140 -100);
PAINT SKYBLUE (4140 -100);
FORCEPROP 1 LAST PART_NUMBER G22026-003
J 0
(4140 -200);
DISPLAY 0.617021 (4140 -200);
PAINT BLUE (4140 -200);
FORCEPROP 1 LASTPIN (4100 -200) $PN 2
J 0
(4105 -190);
DISPLAY 0.617021 (4105 -190);
PAINT GREEN (4105 -190);
FORCEPROP 1 LASTPIN (4100 0) $PN 1
J 0
(4105 -38);
DISPLAY 0.617021 (4105 -38);
PAINT GREEN (4105 -38);
FORCEPROP 1 LAST PACK_TYPE 0603
J 0
(4140 -250);
DISPLAY 0.617021 (4140 -250);
PAINT SKYBLUE (4140 -250);
FORCEPROP 1 LAST MATERIAL CHIP
J 0
(4140 -150);
DISPLAY 0.617021 (4140 -150);
PAINT SKYBLUE (4140 -150);
FORCEPROP 1 LAST TOLERANCE 1%
J 0
(4145 -50);
DISPLAY 0.617021 (4145 -50);
PAINT SKYBLUE (4145 -50);
FORCEPROP 1 LAST LOCATION R4L4
J 0
(4145 50);
DISPLAY 0.617021 (4145 50);
PAINT AQUA (4145 50);
FORCEPROP 1 LAST VALUE 120.0
J 0
(4145 0);
DISPLAY 0.617021 (4145 0);
PAINT SKYBLUE (4145 0);
FORCEPROP 2 LAST CDS_LIB mstr_discrete
J 0
(4100 -100);
PAINT ORANGE (4100 -100);
DISPLAY INVISIBLE (4100 -100);
FORCEPROP 2 LAST CDS_LOCATION R4L4
J 0
(4145 25);
DISPLAY 0.617021 (4145 25);
PAINT AQUA (4145 25);
DISPLAY INVISIBLE (4145 25);
FORCEPROP 1 LAST PATH I58
J 0
(4150 75);
DISPLAY 0.978723 (4150 75);
PAINT GREEN (4150 75);
DISPLAY INVISIBLE (4150 75);
FORCEPROP 2 LAST BOM_COST MEM_VRD_PVPP_DEF
J 0
(4150 75);
PAINT MONO (4150 75);
DISPLAY INVISIBLE (4150 75);
FORCEPROP 2 LAST ROOM VDDQ_DEF_PWR_VR
J 0
(4150 75);
PAINT MONO (4150 75);
DISPLAY INVISIBLE (4150 75);
FORCEPROP 2 LAST $SEC 1
J 0
(4150 125);
PAINT MONO (4150 125);
DISPLAY INVISIBLE (4150 125);
FORCEPROP 2 LAST CDS_SEC 1
J 0
(4150 125);
PAINT MONO (4150 125);
DISPLAY INVISIBLE (4150 125);
FORCEADD GND..1
(-50 1550);
FORCEPROP 3 LASTPIN (-50 1600) SIG_NAME GND\g
J 0
(-40 1610);
DISPLAY 0.659574 (-40 1610);
PAINT MONO (-40 1610);
DISPLAY INVISIBLE (-40 1610);
FORCEPROP 1 LAST HDL_POWER GND
J 0
(-50 1700);
DISPLAY 0.893617 (-50 1700);
PAINT GREEN (-50 1700);
DISPLAY INVISIBLE (-50 1700);
FORCEPROP 1 LAST BODY_TYPE PLUMBING
J 0
(-95 1507);
DISPLAY 0.340426 (-95 1507);
PAINT GREEN (-95 1507);
DISPLAY INVISIBLE (-95 1507);
FORCEPROP 2 LAST ROOM VDDQ_DEF_PWR_VR
J 0
(-600 1625);
PAINT ORANGE (-600 1625);
DISPLAY INVISIBLE (-600 1625);
FORCEPROP 2 LAST BOM_COST MEM_VRD_PVPP_DEF
J 0
(-375 1625);
PAINT MONO (-375 1625);
DISPLAY INVISIBLE (-375 1625);
FORCEPROP 2 LAST CDS_LIB mstr_symbols
J 0
(-50 1550);
PAINT ORANGE (-50 1550);
DISPLAY INVISIBLE (-50 1550);
FORCEPROP 1 LAST VOLTAGE 0
J 0
(-50 1550);
PAINT SKYBLUE (-50 1550);
DISPLAY INVISIBLE (-50 1550);
FORCEPROP 1 LAST PATH I65
J 0
(25 1550);
DISPLAY 1.170213 (25 1550);
PAINT AQUA (25 1550);
DISPLAY INVISIBLE (25 1550);
FORCEPROP 1 LAST SIZE 1B
J 0
(25 1500);
DISPLAY 0.893617 (25 1500);
PAINT GREEN (25 1500);
DISPLAY INVISIBLE (25 1500);
FORCEADD OFFPAGE..1
(-1975 1800);
FORCEPROP 2 LAST $XR0 218 
J 0
(-2257 1800);
DISPLAY 0.638298 (-2257 1800);
PAINT MONO (-2257 1800);
FORCEPROP 2 LAST CDS_LIB mstr_standard
J 0
(-1975 1800);
PAINT ORANGE (-1975 1800);
DISPLAY INVISIBLE (-1975 1800);
FORCEPROP 2 LAST PATH I70
J 0
(-1905 1870);
DISPLAY 1.361702 (-1905 1870);
PAINT ORANGE (-1905 1870);
DISPLAY INVISIBLE (-1905 1870);
FORCEPROP 1 LAST OFFPAGE TRUE
J 0
(-1650 1675);
DISPLAY 0.893617 (-1650 1675);
PAINT GREEN (-1650 1675);
DISPLAY INVISIBLE (-1650 1675);
FORCEPROP 1 LAST COMMENT_BODY TRUE
J 0
(-1850 1700);
DISPLAY 0.893617 (-1850 1700);
PAINT GREEN (-1850 1700);
DISPLAY INVISIBLE (-1850 1700);
FORCEADD OFFPAGE..1
(-1975 2050);
FORCEPROP 2 LAST $XR0 218 
J 0
(-2257 2050);
DISPLAY 0.638298 (-2257 2050);
PAINT MONO (-2257 2050);
FORCEPROP 2 LAST PATH I72
J 0
(-1925 2125);
DISPLAY 1.361702 (-1925 2125);
PAINT ORANGE (-1925 2125);
DISPLAY INVISIBLE (-1925 2125);
FORCEPROP 2 LAST CDS_LIB mstr_standard
J 0
(-1975 2050);
PAINT ORANGE (-1975 2050);
DISPLAY INVISIBLE (-1975 2050);
FORCEPROP 1 LAST OFFPAGE TRUE
J 0
(-1650 1925);
DISPLAY 1.170213 (-1650 1925);
PAINT GREEN (-1650 1925);
DISPLAY INVISIBLE (-1650 1925);
FORCEPROP 1 LAST COMMENT_BODY TRUE
J 0
(-1850 1950);
DISPLAY 1.170213 (-1850 1950);
PAINT GREEN (-1850 1950);
DISPLAY INVISIBLE (-1850 1950);
FORCEADD PVDDQ_DEF..1
(-25 2275);
FORCEPROP 3 LASTPIN (-25 2225) SIG_NAME PVDDQ_DEF\g
J 0
(-15 2235);
DISPLAY 0.659574 (-15 2235);
PAINT MONO (-15 2235);
DISPLAY INVISIBLE (-15 2235);
FORCEPROP 2 LAST ROOM VDDQ_DEF_PWR_VR
J 0
(225 2375);
PAINT ORANGE (225 2375);
DISPLAY INVISIBLE (225 2375);
FORCEPROP 1 LAST PATH I73
J 0
(25 2300);
DISPLAY 0.872340 (25 2300);
PAINT AQUA (25 2300);
DISPLAY INVISIBLE (25 2300);
FORCEPROP 2 LAST BOM_COST MEM_VRD_PVPP_DEF
J 0
(0 2375);
PAINT MONO (0 2375);
DISPLAY INVISIBLE (0 2375);
FORCEPROP 2 LAST CDS_LIB mstr_symbols
J 0
(-25 2275);
PAINT ORANGE (-25 2275);
DISPLAY INVISIBLE (-25 2275);
FORCEPROP 1 LAST VOLTAGE 1.2V
J 0
(-70 2232);
DISPLAY 0.340426 (-70 2232);
PAINT SKYBLUE (-70 2232);
DISPLAY INVISIBLE (-70 2232);
FORCEPROP 1 LAST BODY_TYPE PLUMBING
J 0
(-70 2232);
DISPLAY 0.340426 (-70 2232);
PAINT GREEN (-70 2232);
DISPLAY INVISIBLE (-70 2232);
FORCEPROP 1 LAST HDL_POWER PVDDQ_DEF
J 1
(-25 2325);
DISPLAY 0.872340 (-25 2325);
PAINT GREEN (-25 2325);
DISPLAY INVISIBLE (-25 2325);
FORCEADD RES..2
(-700 1825);
FORCEPROP 1 LAST MATERIAL EMPTY
J 0
(-660 1750);
DISPLAY 0.617021 (-660 1750);
PAINT RED (-660 1750);
FORCEPROP 1 LAST VALUE 100.0
J 0
(-655 1900);
DISPLAY 0.617021 (-655 1900);
PAINT SKYBLUE (-655 1900);
FORCEPROP 1 LAST WATTAGE 1/16W
J 0
(-660 1800);
DISPLAY 0.617021 (-660 1800);
PAINT SKYBLUE (-660 1800);
FORCEPROP 1 LAST PART_NUMBER G21796-017
J 0
(-660 1700);
DISPLAY 0.617021 (-660 1700);
PAINT BLUE (-660 1700);
FORCEPROP 1 LAST PACK_TYPE 0402
J 0
(-660 1650);
DISPLAY 0.617021 (-660 1650);
PAINT SKYBLUE (-660 1650);
FORCEPROP 1 LAST TOLERANCE 1%
J 0
(-655 1850);
DISPLAY 0.617021 (-655 1850);
PAINT SKYBLUE (-655 1850);
FORCEPROP 1 LASTPIN (-700 1725) $PN 2
J 0
(-695 1735);
DISPLAY 0.617021 (-695 1735);
PAINT ORANGE (-695 1735);
FORCEPROP 1 LAST LOCATION R4L2
J 0
(-655 1950);
DISPLAY 0.617021 (-655 1950);
PAINT AQUA (-655 1950);
FORCEPROP 1 LASTPIN (-700 1925) $PN 1
J 0
(-695 1887);
DISPLAY 0.617021 (-695 1887);
PAINT ORANGE (-695 1887);
FORCEPROP 2 LAST SEC 1
J 0
(-650 2075);
DISPLAY 0.680851 (-650 2075);
PAINT MONO (-650 2075);
DISPLAY INVISIBLE (-650 2075);
FORCEPROP 2 LAST SEC_TYPE 0402
J 0
(-650 2075);
DISPLAY 1.021277 (-650 2075);
PAINT ORANGE (-650 2075);
DISPLAY INVISIBLE (-650 2075);
FORCEPROP 1 LAST PATH I74
J 0
(-650 2000);
DISPLAY 1.319149 (-650 2000);
PAINT WHITE (-650 2000);
DISPLAY INVISIBLE (-650 2000);
FORCEPROP 0 LAST ROOM VDDQ_DEF_PWR_VR
J 0
(-650 2000);
DISPLAY 1.021277 (-650 2000);
PAINT ORANGE (-650 2000);
DISPLAY INVISIBLE (-650 2000);
FORCEPROP 2 LAST CDS_LOCATION R4L2
J 0
(-655 1950);
DISPLAY 0.617021 (-655 1950);
PAINT AQUA (-655 1950);
DISPLAY INVISIBLE (-655 1950);
FORCEPROP 2 LAST CDS_LIB mstr_discrete
J 0
(-700 1825);
PAINT ORANGE (-700 1825);
DISPLAY INVISIBLE (-700 1825);
FORCEADD CAPP..1
(2900 -100);
FORCEPROP 0 LAST GROUP PWR_BULK_CAP
J 0
(2965 -299);
DISPLAY 0.638298 (2965 -299);
PAINT BROWN (2965 -299);
DISPLAY BOTH (2965 -299);
FORCEPROP 1 LASTPIN (2900 0) $PN 1
J 0
(2910 -15);
DISPLAY 0.617021 (2910 -15);
PAINT ORANGE (2910 -15);
FORCEPROP 1 LASTPIN (2900 -200) $PN 2
J 0
(2910 -215);
DISPLAY 0.617021 (2910 -215);
PAINT ORANGE (2910 -215);
FORCEPROP 1 LAST PACK_TYPE 3018
J 0
(2950 -200);
DISPLAY 0.617021 (2950 -200);
PAINT SKYBLUE (2950 -200);
FORCEPROP 1 LAST MATERIAL ALUM
J 0
(2950 -150);
DISPLAY 0.617021 (2950 -150);
PAINT SKYBLUE (2950 -150);
FORCEPROP 1 LAST VOLTAGE 2.5V
J 0
(2950 -100);
DISPLAY 0.617021 (2950 -100);
PAINT SKYBLUE (2950 -100);
FORCEPROP 1 LAST TOLERANCE 20%
J 0
(2950 -50);
DISPLAY 0.617021 (2950 -50);
PAINT SKYBLUE (2950 -50);
FORCEPROP 1 LAST VALUE 470UF
J 0
(2950 0);
DISPLAY 0.617021 (2950 0);
PAINT SKYBLUE (2950 0);
FORCEPROP 1 LAST LOCATION C3L6
J 0
(2950 50);
DISPLAY 0.617021 (2950 50);
PAINT AQUA (2950 50);
FORCEPROP 1 LAST PART_NUMBER 699013-049
J 0
(2950 -250);
DISPLAY 0.617021 (2950 -250);
PAINT BLUE (2950 -250);
FORCEPROP 2 LAST SEC 1
J 0
(2950 125);
DISPLAY 0.680851 (2950 125);
PAINT MONO (2950 125);
DISPLAY INVISIBLE (2950 125);
FORCEPROP 2 LAST SEC_TYPE 3018
J 0
(2950 125);
DISPLAY 1.021277 (2950 125);
PAINT ORANGE (2950 125);
DISPLAY INVISIBLE (2950 125);
FORCEPROP 0 LAST ROOM VDDQ_DEF_PWR_VR
J 0
(2950 50);
DISPLAY 1.021277 (2950 50);
PAINT ORANGE (2950 50);
DISPLAY INVISIBLE (2950 50);
FORCEPROP 1 LAST PATH I75
J 0
(2950 50);
DISPLAY 1.319149 (2950 50);
PAINT ORANGE (2950 50);
DISPLAY INVISIBLE (2950 50);
FORCEPROP 2 LAST CDS_LOCATION C3L6
J 0
(2950 0);
DISPLAY 0.617021 (2950 0);
PAINT AQUA (2950 0);
DISPLAY INVISIBLE (2950 0);
FORCEPROP 2 LAST CDS_LIB mstr_discrete
J 0
(2900 -100);
PAINT ORANGE (2900 -100);
DISPLAY INVISIBLE (2900 -100);
FORCEADD CAPP..1
(3200 -100);
FORCEPROP 0 LAST GROUP PWR_BULK_CAP
J 0
(3265 -349);
DISPLAY 0.638298 (3265 -349);
PAINT BROWN (3265 -349);
DISPLAY BOTH (3265 -349);
FORCEPROP 1 LASTPIN (3200 0) $PN 1
J 0
(3210 -15);
DISPLAY 0.617021 (3210 -15);
PAINT ORANGE (3210 -15);
FORCEPROP 1 LASTPIN (3200 -200) $PN 2
J 0
(3210 -215);
DISPLAY 0.617021 (3210 -215);
PAINT ORANGE (3210 -215);
FORCEPROP 1 LAST LOCATION C3L14
J 0
(3250 50);
DISPLAY 0.617021 (3250 50);
PAINT AQUA (3250 50);
FORCEPROP 1 LAST VALUE 470UF
J 0
(3250 0);
DISPLAY 0.617021 (3250 0);
PAINT SKYBLUE (3250 0);
FORCEPROP 1 LAST TOLERANCE 20%
J 0
(3250 -50);
DISPLAY 0.617021 (3250 -50);
PAINT SKYBLUE (3250 -50);
FORCEPROP 1 LAST VOLTAGE 2.5V
J 0
(3250 -100);
DISPLAY 0.617021 (3250 -100);
PAINT SKYBLUE (3250 -100);
FORCEPROP 1 LAST MATERIAL ALUM
J 0
(3250 -150);
DISPLAY 0.617021 (3250 -150);
PAINT SKYBLUE (3250 -150);
FORCEPROP 1 LAST PART_NUMBER 699013-049
J 0
(3250 -250);
DISPLAY 0.617021 (3250 -250);
PAINT BLUE (3250 -250);
FORCEPROP 1 LAST PACK_TYPE 3018
J 0
(3250 -200);
DISPLAY 0.617021 (3250 -200);
PAINT SKYBLUE (3250 -200);
FORCEPROP 2 LAST CDS_LIB mstr_discrete
J 0
(3200 -100);
PAINT ORANGE (3200 -100);
DISPLAY INVISIBLE (3200 -100);
FORCEPROP 2 LAST CDS_LOCATION C3L14
J 0
(3250 0);
DISPLAY 0.617021 (3250 0);
PAINT AQUA (3250 0);
DISPLAY INVISIBLE (3250 0);
FORCEPROP 1 LAST PATH I76
J 0
(3250 50);
DISPLAY 1.319149 (3250 50);
PAINT ORANGE (3250 50);
DISPLAY INVISIBLE (3250 50);
FORCEPROP 0 LAST ROOM VDDQ_DEF_PWR_VR
J 0
(3250 50);
DISPLAY 1.021277 (3250 50);
PAINT ORANGE (3250 50);
DISPLAY INVISIBLE (3250 50);
FORCEPROP 2 LAST SEC_TYPE 3018
J 0
(3250 125);
DISPLAY 1.021277 (3250 125);
PAINT ORANGE (3250 125);
DISPLAY INVISIBLE (3250 125);
FORCEPROP 2 LAST SEC 1
J 0
(3250 125);
DISPLAY 0.680851 (3250 125);
PAINT MONO (3250 125);
DISPLAY INVISIBLE (3250 125);
FORCEADD CAPP..1
(3500 -100);
FORCEPROP 0 LAST GROUP PWR_BULK_CAP
J 0
(3565 -299);
DISPLAY 0.638298 (3565 -299);
PAINT BROWN (3565 -299);
DISPLAY BOTH (3565 -299);
FORCEPROP 1 LASTPIN (3500 0) $PN 1
J 0
(3510 -15);
DISPLAY 0.617021 (3510 -15);
PAINT ORANGE (3510 -15);
FORCEPROP 1 LASTPIN (3500 -200) $PN 2
J 0
(3510 -215);
DISPLAY 0.617021 (3510 -215);
PAINT ORANGE (3510 -215);
FORCEPROP 1 LAST LOCATION C6A5
J 0
(3550 50);
DISPLAY 0.617021 (3550 50);
PAINT AQUA (3550 50);
FORCEPROP 1 LAST VALUE 470UF
J 0
(3550 0);
DISPLAY 0.617021 (3550 0);
PAINT SKYBLUE (3550 0);
FORCEPROP 1 LAST TOLERANCE 20%
J 0
(3550 -50);
DISPLAY 0.617021 (3550 -50);
PAINT SKYBLUE (3550 -50);
FORCEPROP 1 LAST MATERIAL ALUM
J 0
(3550 -150);
DISPLAY 0.617021 (3550 -150);
PAINT SKYBLUE (3550 -150);
FORCEPROP 1 LAST PART_NUMBER 699013-049
J 0
(3550 -250);
DISPLAY 0.617021 (3550 -250);
PAINT BLUE (3550 -250);
FORCEPROP 1 LAST PACK_TYPE 3018
J 0
(3550 -200);
DISPLAY 0.617021 (3550 -200);
PAINT SKYBLUE (3550 -200);
FORCEPROP 1 LAST VOLTAGE 2.5V
J 0
(3550 -100);
DISPLAY 0.617021 (3550 -100);
PAINT SKYBLUE (3550 -100);
FORCEPROP 2 LAST SEC 1
J 0
(3550 125);
DISPLAY 0.680851 (3550 125);
PAINT MONO (3550 125);
DISPLAY INVISIBLE (3550 125);
FORCEPROP 2 LAST SEC_TYPE 3018
J 0
(3550 125);
DISPLAY 1.021277 (3550 125);
PAINT ORANGE (3550 125);
DISPLAY INVISIBLE (3550 125);
FORCEPROP 0 LAST ROOM VDDQ_DEF_PWR_VR
J 0
(3550 50);
DISPLAY 1.021277 (3550 50);
PAINT ORANGE (3550 50);
DISPLAY INVISIBLE (3550 50);
FORCEPROP 1 LAST PATH I77
J 0
(3550 50);
DISPLAY 1.319149 (3550 50);
PAINT ORANGE (3550 50);
DISPLAY INVISIBLE (3550 50);
FORCEPROP 2 LAST CDS_LOCATION C6A5
J 0
(3550 0);
DISPLAY 0.617021 (3550 0);
PAINT AQUA (3550 0);
DISPLAY INVISIBLE (3550 0);
FORCEPROP 2 LAST CDS_LIB mstr_discrete
J 0
(3500 -100);
PAINT ORANGE (3500 -100);
DISPLAY INVISIBLE (3500 -100);
FORCEADD CAPP..1
(3800 -100);
FORCEPROP 0 LAST GROUP PWR_BULK_CAP
J 0
(3865 -349);
DISPLAY 0.638298 (3865 -349);
PAINT BROWN (3865 -349);
DISPLAY BOTH (3865 -349);
FORCEPROP 1 LAST PART_NUMBER 699013-049
J 0
(3850 -250);
DISPLAY 0.617021 (3850 -250);
PAINT BLUE (3850 -250);
FORCEPROP 1 LASTPIN (3800 -200) $PN 2
J 0
(3810 -215);
DISPLAY 0.617021 (3810 -215);
PAINT ORANGE (3810 -215);
FORCEPROP 1 LASTPIN (3800 0) $PN 1
J 0
(3810 -15);
DISPLAY 0.617021 (3810 -15);
PAINT ORANGE (3810 -15);
FORCEPROP 1 LAST LOCATION C4L5
J 0
(3850 50);
DISPLAY 0.617021 (3850 50);
PAINT AQUA (3850 50);
FORCEPROP 1 LAST PACK_TYPE 3018
J 0
(3850 -200);
DISPLAY 0.617021 (3850 -200);
PAINT SKYBLUE (3850 -200);
FORCEPROP 1 LAST MATERIAL ALUM
J 0
(3850 -150);
DISPLAY 0.617021 (3850 -150);
PAINT SKYBLUE (3850 -150);
FORCEPROP 1 LAST VOLTAGE 2.5V
J 0
(3850 -100);
DISPLAY 0.617021 (3850 -100);
PAINT SKYBLUE (3850 -100);
FORCEPROP 1 LAST TOLERANCE 20%
J 0
(3850 -50);
DISPLAY 0.617021 (3850 -50);
PAINT SKYBLUE (3850 -50);
FORCEPROP 1 LAST VALUE 470UF
J 0
(3850 0);
DISPLAY 0.617021 (3850 0);
PAINT SKYBLUE (3850 0);
FORCEPROP 2 LAST SEC_TYPE 3018
J 0
(3850 125);
DISPLAY 1.021277 (3850 125);
PAINT ORANGE (3850 125);
DISPLAY INVISIBLE (3850 125);
FORCEPROP 2 LAST SEC 1
J 0
(3850 125);
DISPLAY 0.680851 (3850 125);
PAINT MONO (3850 125);
DISPLAY INVISIBLE (3850 125);
FORCEPROP 0 LAST ROOM VDDQ_DEF_PWR_VR
J 0
(3850 50);
DISPLAY 1.021277 (3850 50);
PAINT ORANGE (3850 50);
DISPLAY INVISIBLE (3850 50);
FORCEPROP 1 LAST PATH I78
J 0
(3850 50);
DISPLAY 1.319149 (3850 50);
PAINT ORANGE (3850 50);
DISPLAY INVISIBLE (3850 50);
FORCEPROP 2 LAST CDS_LOCATION C4L5
J 0
(3850 0);
DISPLAY 0.617021 (3850 0);
PAINT AQUA (3850 0);
DISPLAY INVISIBLE (3850 0);
FORCEPROP 2 LAST CDS_LIB mstr_discrete
J 0
(3800 -100);
PAINT ORANGE (3800 -100);
DISPLAY INVISIBLE (3800 -100);
FORCEADD PVDDQ_DEF..1
(2900 200);
FORCEPROP 3 LASTPIN (2900 150) SIG_NAME PVDDQ_DEF\g
J 0
(2910 160);
DISPLAY 0.659574 (2910 160);
PAINT MONO (2910 160);
DISPLAY INVISIBLE (2910 160);
FORCEPROP 2 LAST ROOM VDDQ_DEF_PWR_VR
J 0
(3125 300);
PAINT ORANGE (3125 300);
DISPLAY INVISIBLE (3125 300);
FORCEPROP 2 LAST BOM_COST MEM_VRD_PVPP_DEF
J 0
(2950 300);
PAINT MONO (2950 300);
DISPLAY INVISIBLE (2950 300);
FORCEPROP 1 LAST PATH I80
J 0
(2950 225);
DISPLAY 0.872340 (2950 225);
PAINT AQUA (2950 225);
DISPLAY INVISIBLE (2950 225);
FORCEPROP 2 LAST CDS_LIB mstr_symbols
J 0
(2900 200);
PAINT ORANGE (2900 200);
DISPLAY INVISIBLE (2900 200);
FORCEPROP 1 LAST VOLTAGE 1.2V
J 0
(2855 157);
DISPLAY 0.340426 (2855 157);
PAINT SKYBLUE (2855 157);
DISPLAY INVISIBLE (2855 157);
FORCEPROP 1 LAST BODY_TYPE PLUMBING
J 0
(2855 157);
DISPLAY 0.340426 (2855 157);
PAINT GREEN (2855 157);
DISPLAY INVISIBLE (2855 157);
FORCEPROP 1 LAST HDL_POWER PVDDQ_DEF
J 1
(2900 250);
DISPLAY 0.872340 (2900 250);
PAINT GREEN (2900 250);
DISPLAY INVISIBLE (2900 250);
FORCEADD GND..1
(2900 -575);
FORCEPROP 3 LASTPIN (2900 -525) SIG_NAME GND\g
J 0
(2910 -515);
DISPLAY 0.659574 (2910 -515);
PAINT MONO (2910 -515);
DISPLAY INVISIBLE (2910 -515);
FORCEPROP 1 LAST HDL_POWER GND
J 0
(2900 -425);
DISPLAY 0.893617 (2900 -425);
PAINT GREEN (2900 -425);
DISPLAY INVISIBLE (2900 -425);
FORCEPROP 1 LAST BODY_TYPE PLUMBING
J 0
(2855 -618);
DISPLAY 0.340426 (2855 -618);
PAINT GREEN (2855 -618);
DISPLAY INVISIBLE (2855 -618);
FORCEPROP 1 LAST PATH I81
J 0
(2975 -575);
DISPLAY 1.170213 (2975 -575);
PAINT AQUA (2975 -575);
DISPLAY INVISIBLE (2975 -575);
FORCEPROP 2 LAST CDS_LIB mstr_symbols
J 0
(2900 -575);
PAINT ORANGE (2900 -575);
DISPLAY INVISIBLE (2900 -575);
FORCEPROP 1 LAST SIZE 1B
J 0
(2975 -625);
DISPLAY 0.893617 (2975 -625);
PAINT GREEN (2975 -625);
DISPLAY INVISIBLE (2975 -625);
FORCEPROP 1 LAST VOLTAGE 0
J 0
(2900 -575);
PAINT SKYBLUE (2900 -575);
DISPLAY INVISIBLE (2900 -575);
FORCEADD PVDDQ_DEF..1
(2400 3100);
FORCEPROP 3 LASTPIN (2400 3050) SIG_NAME PVDDQ_DEF\g
J 0
(2410 3060);
DISPLAY 0.659574 (2410 3060);
PAINT MONO (2410 3060);
DISPLAY INVISIBLE (2410 3060);
FORCEPROP 2 LAST ROOM VDDQ_DEF_PWR_VR
J 0
(2650 3200);
PAINT ORANGE (2650 3200);
DISPLAY INVISIBLE (2650 3200);
FORCEPROP 2 LAST BOM_COST MEM_VRD_PVDDQ_DEF
J 0
(2475 3200);
PAINT MONO (2475 3200);
DISPLAY INVISIBLE (2475 3200);
FORCEPROP 2 LAST CDS_LIB mstr_symbols
J 0
(2400 3100);
PAINT ORANGE (2400 3100);
DISPLAY INVISIBLE (2400 3100);
FORCEPROP 1 LAST PATH I93
J 0
(2450 3125);
DISPLAY 0.872340 (2450 3125);
PAINT AQUA (2450 3125);
DISPLAY INVISIBLE (2450 3125);
FORCEPROP 1 LAST VOLTAGE 1.2V
J 0
(2355 3057);
DISPLAY 0.340426 (2355 3057);
PAINT SKYBLUE (2355 3057);
DISPLAY INVISIBLE (2355 3057);
FORCEPROP 1 LAST BODY_TYPE PLUMBING
J 0
(2355 3057);
DISPLAY 0.340426 (2355 3057);
PAINT GREEN (2355 3057);
DISPLAY INVISIBLE (2355 3057);
FORCEPROP 1 LAST HDL_POWER PVDDQ_DEF
J 1
(2400 3150);
DISPLAY 0.872340 (2400 3150);
PAINT GREEN (2400 3150);
DISPLAY INVISIBLE (2400 3150);
FORCEADD GND..1
(2400 2350);
FORCEPROP 3 LASTPIN (2400 2400) SIG_NAME GND\g
J 0
(2410 2410);
DISPLAY 0.659574 (2410 2410);
PAINT MONO (2410 2410);
DISPLAY INVISIBLE (2410 2410);
FORCEPROP 1 LAST VOLTAGE 0
J 0
(2400 2350);
PAINT SKYBLUE (2400 2350);
DISPLAY INVISIBLE (2400 2350);
FORCEPROP 1 LAST SIZE 1B
J 0
(2475 2300);
DISPLAY 0.893617 (2475 2300);
PAINT GREEN (2475 2300);
DISPLAY INVISIBLE (2475 2300);
FORCEPROP 2 LAST CDS_LIB mstr_symbols
J 0
(2400 2350);
PAINT ORANGE (2400 2350);
DISPLAY INVISIBLE (2400 2350);
FORCEPROP 1 LAST PATH I94
J 0
(2475 2350);
DISPLAY 1.170213 (2475 2350);
PAINT AQUA (2475 2350);
DISPLAY INVISIBLE (2475 2350);
FORCEPROP 2 LAST BOM_COST MEM_VRD_PVDDQ_DEF
J 0
(2075 2425);
PAINT MONO (2075 2425);
DISPLAY INVISIBLE (2075 2425);
FORCEPROP 2 LAST ROOM VDDQ_DEF_PWR_VR
J 0
(1850 2425);
PAINT ORANGE (1850 2425);
DISPLAY INVISIBLE (1850 2425);
FORCEPROP 1 LAST BODY_TYPE PLUMBING
J 0
(2355 2307);
DISPLAY 0.340426 (2355 2307);
PAINT GREEN (2355 2307);
DISPLAY INVISIBLE (2355 2307);
FORCEPROP 1 LAST HDL_POWER GND
J 0
(2400 2500);
DISPLAY 0.893617 (2400 2500);
PAINT GREEN (2400 2500);
DISPLAY INVISIBLE (2400 2500);
FORCEADD DNS..3
(-295 2070);
PAINT RED (-295 2070);
FORCEPROP 2 LAST CDS_LIB mstr_misc
J 0
(-295 2070);
PAINT ORANGE (-295 2070);
DISPLAY INVISIBLE (-295 2070);
FORCEPROP 1 LAST COMMENT_BODY TRUE
R 1
J 0
(-220 1845);
DISPLAY 0.872340 (-220 1845);
PAINT GREEN (-220 1845);
DISPLAY INVISIBLE (-220 1845);
FORCEADD DNS..2
(-695 1820);
PAINT RED (-695 1820);
FORCEPROP 2 LAST CDS_LIB mstr_misc
J 0
(-695 1820);
PAINT ORANGE (-695 1820);
DISPLAY INVISIBLE (-695 1820);
FORCEPROP 1 LAST COMMENT_BODY TRUE
R 1
J 0
(-620 1595);
DISPLAY 0.872340 (-620 1595);
PAINT GREEN (-620 1595);
DISPLAY INVISIBLE (-620 1595);
FORCEADD INTEL_CORP_BPAGE..1
(5475 -1550);
FORCEPROP 1 LAST CDS_CON_LAST_MODIFIED Fri Jun 16 17:49:19 2017
J 0
(4050 -1225);
PAINT GREEN (4050 -1225);
DISPLAY INVISIBLE (4050 -1225);
FORCEPROP 1 LAST CUSTOM_TXT_CDS <CURRENT_DESIGN_SHEET> OF <TOTAL_DESIGN_SHEETS>
J 0
(4975 -1525);
PAINT ORANGE (4975 -1525);
FORCEPROP 2 LAST CUSTOM_TXT_CDS <XR_PAGE_TITLE>
J 0
(-2415 3700);
DISPLAY 0.638298 (-2415 3700);
PAINT PINK (-2415 3700);
DISPLAY INVISIBLE (-2415 3700);
FORCEPROP 2 LAST CUSTOM_TXT_CDS <CON_LAST_MODIFIED>
J 0
(1475 -1450);
PAINT ORANGE (1475 -1450);
FORCEPROP 2 LAST CUSTOM_TXT_CDS <CON_PAGE_NUM> OF <CON_TOTAL_PAGES>
J 0
(4975 -1525);
PAINT GREEN (4975 -1525);
FORCEPROP 1 LAST SCH_TITLE VDDQ DEF DECAP (3 OF 3)
J 0
(-2475 -1500);
DISPLAY 1.212766 (-2475 -1500);
PAINT GREEN (-2475 -1500);
FORCEPROP 2 LAST CDS_XR_PAGE_TITLE CR-220 : @BASEBOARD_FAB2_LIB.BASEBOARD_FAB2(SCH_1):PAGE220
J 0
(-2415 3700);
DISPLAY 0.638298 (-2415 3700);
PAINT PINK (-2415 3700);
DISPLAY INVISIBLE (-2415 3700);
FORCEPROP 2 LAST CDS_LIB mstr_symbols
J 0
(5475 -1550);
PAINT ORANGE (5475 -1550);
DISPLAY INVISIBLE (5475 -1550);
FORCEPROP 2 LAST PAGE_BORDER TRUE
J 0
(-2415 3700);
DISPLAY 0.851064 (-2415 3700);
PAINT PINK (-2415 3700);
DISPLAY INVISIBLE (-2415 3700);
FORCEPROP 2 LAST ROOM VDDQ_DEF_PWR_VR
J 0
(-2625 3550);
PAINT ORANGE (-2625 3550);
DISPLAY INVISIBLE (-2625 3550);
FORCEPROP 1 LAST COMMENT_BODY TRUE
J 0
(5487 -1538);
DISPLAY 0.446809 (5487 -1538);
PAINT GREEN (5487 -1538);
DISPLAY INVISIBLE (5487 -1538);
FORCEADD DNS..3
(-320 1620);
PAINT RED (-320 1620);
FORCEPROP 2 LAST CDS_LIB mstr_misc
J 0
(-320 1620);
PAINT ORANGE (-320 1620);
DISPLAY INVISIBLE (-320 1620);
FORCEPROP 1 LAST COMMENT_BODY TRUE
R 1
J 0
(-245 1395);
DISPLAY 0.872340 (-245 1395);
PAINT GREEN (-245 1395);
DISPLAY INVISIBLE (-245 1395);
WIRE 16 -1 (2675 1850)(2675 1900);
WIRE 16 -1 (2675 1850)(3025 1850);
WIRE 16 -1 (2675 1850)(2675 1775);
WIRE 16 -1 (3425 1850)(3025 1850);
WIRE 16 -1 (3025 1775)(3025 1850);
WIRE 16 -1 (3775 1850)(3425 1850);
WIRE 16 -1 (3425 1775)(3425 1850);
WIRE 16 -1 (4125 1850)(3775 1850);
WIRE 16 -1 (3775 1775)(3775 1850);
WIRE 16 -1 (4525 1850)(4125 1850);
WIRE 16 -1 (4125 1775)(4125 1850);
WIRE 16 -1 (4525 1775)(4525 1850);
WIRE 16 -1 (4400 1350)(4400 1425);
WIRE 16 -1 (4400 1425)(4125 1425);
WIRE 16 -1 (4400 1425)(4525 1425);
WIRE 16 -1 (4525 1575)(4525 1425);
WIRE 16 -1 (3775 1425)(4125 1425);
WIRE 16 -1 (4125 1575)(4125 1425);
WIRE 16 -1 (3425 1425)(3775 1425);
WIRE 16 -1 (3775 1575)(3775 1425);
WIRE 16 -1 (3025 1425)(3425 1425);
WIRE 16 -1 (3425 1575)(3425 1425);
WIRE 16 -1 (2675 1425)(3025 1425);
WIRE 16 -1 (3025 1575)(3025 1425);
WIRE 16 -1 (2675 1575)(2675 1425);
WIRE 16 -1 (1900 1300)(1900 1450);
WIRE 16 -1 (1900 1300)(1600 1300);
WIRE 16 -1 (1900 1300)(1900 1100);
WIRE 16 -1 (1300 1300)(1600 1300);
WIRE 16 -1 (1600 1100)(1600 1300);
WIRE 16 -1 (1000 1300)(1300 1300);
WIRE 16 -1 (1300 1100)(1300 1300);
WIRE 16 -1 (1000 1300)(700 1300);
WIRE 16 -1 (1000 1100)(1000 1300);
WIRE 16 -1 (400 1300)(700 1300);
WIRE 16 -1 (700 1300)(700 1100);
WIRE 16 -1 (100 1300)(400 1300);
WIRE 16 -1 (400 1100)(400 1300);
WIRE 16 -1 (-200 1300)(100 1300);
WIRE 16 -1 (100 1100)(100 1300);
WIRE 16 -1 (-200 1300)(-500 1300);
WIRE 16 -1 (-200 1100)(-200 1300);
WIRE 16 -1 (-500 1300)(-1450 1300);
WIRE 16 -1 (-500 1100)(-500 1300);
WIRE 16 -1 (-1800 1300)(-1450 1300);
WIRE 16 -1 (-1450 1100)(-1450 1300);
WIRE 16 -1 (-2250 1375)(-2250 1300);
WIRE 16 -1 (-2100 1300)(-2250 1300);
WIRE 16 -1 (-400 2675)(-400 2725);
WIRE 16 -1 (-750 2725)(-400 2725);
WIRE 16 -1 (-400 2875)(-400 2725);
WIRE 16 -1 (-1100 2725)(-750 2725);
WIRE 16 -1 (-750 2875)(-750 2725);
WIRE 16 -1 (-1450 2725)(-1100 2725);
WIRE 16 -1 (-1100 2875)(-1100 2725);
WIRE 16 -1 (-1450 2875)(-1450 2725);
WIRE 16 -1 (-2300 3150)(-2300 3200);
WIRE 16 -1 (-2300 3150)(-1950 3150);
WIRE 16 -1 (-2300 3150)(-2300 3075);
WIRE 16 -1 (-1950 3075)(-1950 3150);
WIRE 16 -1 (2650 1125)(2650 1175);
WIRE 16 -1 (2650 1125)(3000 1125);
WIRE 16 -1 (2650 1125)(2650 1050);
WIRE 16 -1 (3400 1125)(3000 1125);
WIRE 16 -1 (3000 1050)(3000 1125);
WIRE 16 -1 (3400 1050)(3400 1125);
WIRE 16 -1 (3600 650)(3600 700);
WIRE 16 -1 (3600 700)(3400 700);
WIRE 16 -1 (3000 700)(3400 700);
WIRE 16 -1 (3400 850)(3400 700);
WIRE 16 -1 (2650 700)(3000 700);
WIRE 16 -1 (3000 850)(3000 700);
WIRE 16 -1 (2650 850)(2650 700);
WIRE 16 -1 (-1450 3150)(-1450 3200);
WIRE 16 -1 (-1100 3150)(-1450 3150);
WIRE 16 -1 (-1450 3075)(-1450 3150);
WIRE 16 -1 (-750 3150)(-1100 3150);
WIRE 16 -1 (-1100 3075)(-1100 3150);
WIRE 16 -1 (-400 3150)(-750 3150);
WIRE 16 -1 (-750 3075)(-750 3150);
WIRE 16 -1 (-400 3075)(-400 3150);
WIRE 16 -1 (-1950 2525)(-1950 2550);
WIRE 16 -1 (-2300 2550)(-1950 2550);
WIRE 16 -1 (-1950 2875)(-1950 2550);
WIRE 16 -1 (-2300 2875)(-2300 2550);
WIRE 16 -1 (-2150 250)(-2150 300);
WIRE 16 -1 (-2150 250)(-1850 250);
WIRE 16 -1 (-2150 200)(-2150 250);
WIRE 16 -1 (-1850 250)(-1550 250);
WIRE 16 -1 (-1850 200)(-1850 250);
WIRE 16 -1 (-1550 250)(-1275 250);
WIRE 16 -1 (-1550 200)(-1550 250);
WIRE 16 -1 (-1000 250)(-1275 250);
WIRE 16 -1 (-1275 200)(-1275 250);
WIRE 16 -1 (-700 250)(-1000 250);
WIRE 16 -1 (-1000 200)(-1000 250);
WIRE 16 -1 (-400 250)(-700 250);
WIRE 16 -1 (-700 200)(-700 250);
WIRE 16 -1 (-125 250)(-400 250);
WIRE 16 -1 (-400 200)(-400 250);
WIRE 16 -1 (200 250)(-125 250);
WIRE 16 -1 (-125 200)(-125 250);
WIRE 16 -1 (500 250)(200 250);
WIRE 16 -1 (200 200)(200 250);
WIRE 16 -1 (800 250)(500 250);
WIRE 16 -1 (500 200)(500 250);
WIRE 16 -1 (1075 250)(800 250);
WIRE 16 -1 (800 200)(800 250);
WIRE 16 -1 (1350 250)(1075 250);
WIRE 16 -1 (1075 200)(1075 250);
WIRE 16 -1 (1650 250)(1350 250);
WIRE 16 -1 (1350 200)(1350 250);
WIRE 16 -1 (1950 250)(1650 250);
WIRE 16 -1 (1650 200)(1650 250);
WIRE 16 -1 (2225 250)(1950 250);
WIRE 16 -1 (1950 200)(1950 250);
WIRE 16 -1 (2225 200)(2225 250);
WIRE 16 -1 (-2150 -125)(-2150 -175);
WIRE 16 -1 (-1850 -125)(-2150 -125);
WIRE 16 -1 (-2150 0)(-2150 -125);
WIRE 16 -1 (-1550 -125)(-1850 -125);
WIRE 16 -1 (-1850 0)(-1850 -125);
WIRE 16 -1 (-1550 -125)(-1275 -125);
WIRE 16 -1 (-1550 0)(-1550 -125);
WIRE 16 -1 (-1000 -125)(-1275 -125);
WIRE 16 -1 (-1275 0)(-1275 -125);
WIRE 16 -1 (-700 -125)(-1000 -125);
WIRE 16 -1 (-1000 0)(-1000 -125);
WIRE 16 -1 (-400 -125)(-700 -125);
WIRE 16 -1 (-700 0)(-700 -125);
WIRE 16 -1 (-125 -125)(-400 -125);
WIRE 16 -1 (-400 0)(-400 -125);
WIRE 16 -1 (200 -125)(-125 -125);
WIRE 16 -1 (-125 0)(-125 -125);
WIRE 16 -1 (500 -125)(200 -125);
WIRE 16 -1 (200 0)(200 -125);
WIRE 16 -1 (800 -125)(500 -125);
WIRE 16 -1 (500 0)(500 -125);
WIRE 16 -1 (1075 -125)(800 -125);
WIRE 16 -1 (800 0)(800 -125);
WIRE 16 -1 (1350 -125)(1075 -125);
WIRE 16 -1 (1075 0)(1075 -125);
WIRE 16 -1 (1650 -125)(1350 -125);
WIRE 16 -1 (1350 0)(1350 -125);
WIRE 16 -1 (1950 -125)(1650 -125);
WIRE 16 -1 (1650 0)(1650 -125);
WIRE 16 -1 (2225 -125)(1950 -125);
WIRE 16 -1 (1950 0)(1950 -125);
WIRE 16 -1 (2225 0)(2225 -125);
WIRE 16 -1 (-2150 -500)(-2150 -450);
WIRE 16 -1 (-2150 -500)(-1850 -500);
WIRE 16 -1 (-2150 -550)(-2150 -500);
WIRE 16 -1 (-1850 -500)(-1550 -500);
WIRE 16 -1 (-1850 -550)(-1850 -500);
WIRE 16 -1 (-1550 -500)(-1275 -500);
WIRE 16 -1 (-1550 -550)(-1550 -500);
WIRE 16 -1 (-1000 -500)(-1275 -500);
WIRE 16 -1 (-1275 -550)(-1275 -500);
WIRE 16 -1 (-700 -500)(-1000 -500);
WIRE 16 -1 (-1000 -550)(-1000 -500);
WIRE 16 -1 (-400 -500)(-700 -500);
WIRE 16 -1 (-700 -550)(-700 -500);
WIRE 16 -1 (-125 -500)(-400 -500);
WIRE 16 -1 (-400 -550)(-400 -500);
WIRE 16 -1 (200 -500)(-125 -500);
WIRE 16 -1 (-125 -550)(-125 -500);
WIRE 16 -1 (500 -500)(200 -500);
WIRE 16 -1 (200 -550)(200 -500);
WIRE 16 -1 (800 -500)(500 -500);
WIRE 16 -1 (500 -550)(500 -500);
WIRE 16 -1 (1075 -500)(800 -500);
WIRE 16 -1 (800 -550)(800 -500);
WIRE 16 -1 (1350 -500)(1075 -500);
WIRE 16 -1 (1075 -550)(1075 -500);
WIRE 16 -1 (1650 -500)(1350 -500);
WIRE 16 -1 (1350 -550)(1350 -500);
WIRE 16 -1 (1950 -500)(1650 -500);
WIRE 16 -1 (1650 -550)(1650 -500);
WIRE 16 -1 (2225 -500)(1950 -500);
WIRE 16 -1 (1950 -550)(1950 -500);
WIRE 16 -1 (2225 -550)(2225 -500);
WIRE 16 -1 (-2150 -900)(-2150 -950);
WIRE 16 -1 (-1850 -900)(-2150 -900);
WIRE 16 -1 (-2150 -750)(-2150 -900);
WIRE 16 -1 (-1550 -900)(-1850 -900);
WIRE 16 -1 (-1850 -750)(-1850 -900);
WIRE 16 -1 (-1550 -900)(-1275 -900);
WIRE 16 -1 (-1550 -750)(-1550 -900);
WIRE 16 -1 (-1000 -900)(-1275 -900);
WIRE 16 -1 (-1275 -750)(-1275 -900);
WIRE 16 -1 (-700 -900)(-1000 -900);
WIRE 16 -1 (-1000 -750)(-1000 -900);
WIRE 16 -1 (-400 -900)(-700 -900);
WIRE 16 -1 (-700 -750)(-700 -900);
WIRE 16 -1 (-125 -900)(-400 -900);
WIRE 16 -1 (-400 -750)(-400 -900);
WIRE 16 -1 (200 -900)(-125 -900);
WIRE 16 -1 (-125 -750)(-125 -900);
WIRE 16 -1 (500 -900)(200 -900);
WIRE 16 -1 (200 -750)(200 -900);
WIRE 16 -1 (800 -900)(500 -900);
WIRE 16 -1 (500 -750)(500 -900);
WIRE 16 -1 (1075 -900)(800 -900);
WIRE 16 -1 (800 -750)(800 -900);
WIRE 16 -1 (1350 -900)(1075 -900);
WIRE 16 -1 (1075 -750)(1075 -900);
WIRE 16 -1 (1650 -900)(1350 -900);
WIRE 16 -1 (1350 -750)(1350 -900);
WIRE 16 -1 (1950 -900)(1650 -900);
WIRE 16 -1 (1650 -750)(1650 -900);
WIRE 16 -1 (2225 -900)(1950 -900);
WIRE 16 -1 (1950 -750)(1950 -900);
WIRE 16 -1 (2225 -750)(2225 -900);
WIRE 16 -1 (175 2575)(175 2600);
WIRE 16 -1 (175 2600)(500 2600);
WIRE 16 -1 (175 2825)(175 2600);
WIRE 16 -1 (500 2600)(800 2600);
WIRE 16 -1 (500 2825)(500 2600);
WIRE 16 -1 (800 2600)(800 2825);
WIRE 16 -1 (175 3075)(175 3150);
WIRE 16 -1 (500 3075)(175 3075);
WIRE 16 -1 (175 3025)(175 3075);
WIRE 16 -1 (800 3075)(500 3075);
WIRE 16 -1 (500 3025)(500 3075);
WIRE 16 -1 (800 3025)(800 3075);
WIRE 16 -1 (1550 1800)(1550 1750);
WIRE 16 -1 (1200 1800)(1550 1800);
WIRE 16 -1 (1550 1800)(1550 1950);
WIRE 16 -1 (850 1800)(1200 1800);
WIRE 16 -1 (1200 1950)(1200 1800);
WIRE 16 -1 (500 1800)(850 1800);
WIRE 16 -1 (850 1950)(850 1800);
WIRE 16 -1 (500 1950)(500 1800);
WIRE 16 -1 (500 2250)(500 2200);
WIRE 16 -1 (500 2200)(850 2200);
WIRE 16 -1 (500 2200)(500 2150);
WIRE 16 -1 (850 2200)(1200 2200);
WIRE 16 -1 (850 2200)(850 2150);
WIRE 16 -1 (1200 2200)(1550 2200);
WIRE 16 -1 (1200 2200)(1200 2150);
WIRE 16 -1 (1550 2200)(1550 2150);
WIRE 16 -1 (1600 2850)(1600 2800);
WIRE 16 -1 (1600 3100)(1600 3050);
WIRE 16 -1 (1900 775)(1900 800);
WIRE 16 -1 (1900 800)(1600 800);
WIRE 16 -1 (1900 800)(1900 950);
WIRE 16 -1 (1300 800)(1600 800);
WIRE 16 -1 (1600 800)(1600 950);
WIRE 16 -1 (1000 800)(1300 800);
WIRE 16 -1 (1300 800)(1300 950);
WIRE 16 -1 (1000 800)(700 800);
WIRE 16 -1 (1000 800)(1000 950);
WIRE 16 -1 (400 800)(700 800);
WIRE 16 -1 (700 800)(700 950);
WIRE 16 -1 (100 800)(400 800);
WIRE 16 -1 (400 800)(400 950);
WIRE 16 -1 (-200 800)(100 800);
WIRE 16 -1 (100 800)(100 950);
WIRE 16 -1 (-200 800)(-500 800);
WIRE 16 -1 (-200 800)(-200 950);
WIRE 16 -1 (-500 800)(-1450 800);
WIRE 16 -1 (-500 800)(-500 950);
WIRE 16 -1 (-1450 950)(-1450 800);
WIRE 16 -1 (-50 1600)(-50 1625);
WIRE 16 -1 (-50 1625)(-175 1625);
WIRE 16 -1 (-25 2225)(-25 2075);
WIRE 16 -1 (-25 2075)(-150 2075);
WIRE 16 -1 (2900 100)(2900 150);
WIRE 16 -1 (3200 100)(2900 100);
WIRE 16 -1 (2900 0)(2900 100);
WIRE 16 -1 (3500 100)(3200 100);
WIRE 16 -1 (3200 0)(3200 100);
WIRE 16 -1 (3800 100)(3500 100);
WIRE 16 -1 (3500 0)(3500 100);
WIRE 16 -1 (4100 100)(3800 100);
WIRE 16 -1 (3800 0)(3800 100);
WIRE 16 -1 (4100 0)(4100 100);
WIRE 16 -1 (2900 -400)(2900 -525);
WIRE 16 -1 (3200 -400)(2900 -400);
WIRE 16 -1 (2900 -400)(2900 -200);
WIRE 16 -1 (3500 -400)(3200 -400);
WIRE 16 -1 (3200 -200)(3200 -400);
WIRE 16 -1 (3800 -400)(3500 -400);
WIRE 16 -1 (3500 -200)(3500 -400);
WIRE 16 -1 (4100 -400)(3800 -400);
WIRE 16 -1 (3800 -200)(3800 -400);
WIRE 16 -1 (4100 -200)(4100 -400);
WIRE 16 -1 (2400 3000)(2400 3050);
WIRE 16 -1 (2400 3000)(2750 3000);
WIRE 16 -1 (2400 3000)(2400 2925);
WIRE 16 -1 (3150 3000)(2750 3000);
WIRE 16 -1 (2750 2925)(2750 3000);
WIRE 16 -1 (3500 3000)(3150 3000);
WIRE 16 -1 (3150 2925)(3150 3000);
WIRE 16 -1 (3850 3000)(3500 3000);
WIRE 16 -1 (3500 2925)(3500 3000);
WIRE 16 -1 (4250 3000)(3850 3000);
WIRE 16 -1 (3850 2925)(3850 3000);
WIRE 16 -1 (4600 3000)(4250 3000);
WIRE 16 -1 (4250 2925)(4250 3000);
WIRE 16 -1 (5000 3000)(4600 3000);
WIRE 16 -1 (4600 2925)(4600 3000);
WIRE 16 -1 (5000 2925)(5000 3000);
WIRE 16 -1 (2400 2400)(2400 2450);
WIRE 16 -1 (2400 2450)(2750 2450);
WIRE 16 -1 (2400 2725)(2400 2450);
WIRE 16 -1 (2750 2450)(3150 2450);
WIRE 16 -1 (2750 2725)(2750 2450);
WIRE 16 -1 (3150 2450)(3500 2450);
WIRE 16 -1 (3150 2725)(3150 2450);
WIRE 16 -1 (3500 2450)(3850 2450);
WIRE 16 -1 (3500 2725)(3500 2450);
WIRE 16 -1 (4250 2450)(3850 2450);
WIRE 16 -1 (3850 2725)(3850 2450);
WIRE 16 -1 (4250 2450)(4600 2450);
WIRE 16 -1 (4250 2725)(4250 2450);
WIRE 16 -1 (4600 2450)(5000 2450);
WIRE 16 -1 (4600 2725)(4600 2450);
WIRE 16 -1 (5000 2725)(5000 2450);
WIRE 3 682 (1875 2550)(1400 2550);
WIRE 3 682 (1400 2550)(1400 3250);
WIRE 3 682 (1875 3250)(1875 2550);
WIRE 3 682 (1875 3250)(1400 3250);
WIRE 3 682 (0 2500)(0 3300);
WIRE 3 682 (1300 2500)(0 2500);
WIRE 3 682 (1300 3300)(0 3300);
WIRE 3 682 (1300 3300)(1300 2500);
WIRE 3 682 (300 1650)(1850 1650);
WIRE 3 682 (300 2400)(300 1650);
WIRE 3 682 (1850 1650)(1850 2400);
WIRE 3 682 (1850 2400)(300 2400);
WIRE 16 682 (-2425 2400)(-2425 3400);
WIRE 16 682 (-100 2400)(-2425 2400);
WIRE 16 682 (-100 3400)(-2425 3400);
WIRE 16 682 (-100 3400)(-100 2400);
WIRE 3 682 (-2375 2450)(-2375 3125);
WIRE 3 682 (-1675 2450)(-2375 2450);
WIRE 3 682 (-2375 3125)(-1675 3125);
WIRE 3 682 (-1675 3125)(-1675 2450);
WIRE 3 682 (-1600 700)(-1600 1400);
WIRE 3 682 (2150 700)(-1600 700);
WIRE 3 682 (2150 1400)(-1600 1400);
WIRE 3 682 (2150 1400)(2150 700);
WIRE 3 682 (2700 525)(-2375 525);
WIRE 3 682 (2700 -1025)(2700 525);
WIRE 3 682 (-2375 525)(-2375 -1025);
WIRE 3 682 (-2375 -1025)(2700 -1025);
WIRE 3 682 (-1550 1250)(-1550 850);
WIRE 3 682 (-850 1250)(-1550 1250);
WIRE 3 682 (-1550 850)(-850 850);
WIRE 3 682 (-850 850)(-850 1250);
WIRE 16 -1 (-700 1925)(-700 2075);
WIRE 16 -1 (-450 2075)(-700 2075);
WIRE 16 -1 (-700 2075)(-800 2075);
WIRE 16 -1 (-800 2075)(-800 1925);
WIRE 16 -1 (-1200 2050)(-1925 2050);
FORCEPROP 2 LAST SIG_NAME VSENSE_PVDDQ_DEF_P
J 0
(-1930 2065);
DISPLAY 0.617021 (-1930 2065);
PAINT ORANGE (-1930 2065);
WIRE 16 -1 (-800 1925)(-1200 1925);
WIRE 16 -1 (-1200 1925)(-1200 2050);
WIRE 16 -1 (-700 1725)(-700 1625);
WIRE 16 -1 (-475 1625)(-700 1625);
WIRE 16 -1 (-700 1625)(-800 1625);
WIRE 16 -1 (-800 1850)(-800 1625);
WIRE 16 -1 (-1200 1850)(-800 1850);
WIRE 16 -1 (-1200 1800)(-1200 1850);
WIRE 16 -1 (-1925 1800)(-1200 1800);
FORCEPROP 2 LAST SIG_NAME VSENSE_PVDDQ_DEF_N
J 0
(-1935 1810);
DISPLAY 0.617021 (-1935 1810);
PAINT ORANGE (-1935 1810);
WIRE 16 2175 (2200 475)(2200 3325);
WIRE 16 2175 (5400 475)(2200 475);
WIRE 16 2175 (2200 3325)(5400 3325);
WIRE 16 2175 (5400 3325)(5400 475);
WIRE 3 682 (2150 2025)(2350 2025);
WIRE 3 682 (2350 2025)(2350 575);
WIRE 3 682 (2150 3200)(2150 2025);
WIRE 3 682 (5375 3200)(2150 3200);
WIRE 3 682 (2350 575)(5375 575);
WIRE 3 682 (5375 575)(5375 3200);
WIRE 3 682 (-1600 2600)(-150 2600);
WIRE 3 682 (-150 3350)(-150 2600);
WIRE 3 682 (-1600 3350)(-1600 2600);
WIRE 3 682 (-1600 3350)(-150 3350);
WIRE 3 682 (4050 1275)(4050 525);
WIRE 3 682 (4050 525)(4175 525);
WIRE 16 682 (2750 -700)(5225 -700);
WIRE 16 682 (2750 300)(2750 -700);
WIRE 16 682 (5225 -700)(5225 300);
WIRE 16 682 (5225 300)(2750 300);
WIRE 16 2175 (2250 2225)(5325 2225);
DOT 1 (-500 800);
DOT 1 (2400 3000);
DOT 1 (175 2600);
DOT 1 (1550 1800);
DOT 1 (4125 1850);
DOT 1 (4250 2450);
DOT 1 (3025 1850);
DOT 1 (2400 2450);
DOT 1 (2750 3000);
DOT 1 (3425 1425);
DOT 1 (500 2600);
DOT 1 (-1100 3150);
DOT 1 (-1275 -500);
DOT 1 (3850 2450);
DOT 1 (-1275 250);
DOT 1 (-700 250);
DOT 1 (400 1300);
DOT 1 (400 800);
DOT 1 (1000 800);
DOT 1 (1300 800);
DOT 1 (1600 800);
DOT 1 (-1450 1300);
DOT 1 (800 250);
DOT 1 (100 800);
DOT 1 (4600 2450);
DOT 1 (-700 2075);
DOT 1 (-1950 2550);
DOT 1 (-700 -900);
DOT 1 (-2150 -125);
DOT 1 (-1850 250);
DOT 1 (-1000 -900);
DOT 1 (-1550 -900);
DOT 1 (-1850 -900);
DOT 1 (850 2200);
DOT 1 (1200 2200);
DOT 1 (1200 1800);
DOT 1 (850 1800);
DOT 1 (1650 -900);
DOT 1 (1350 -900);
DOT 1 (200 -900);
DOT 1 (-125 -900);
DOT 1 (-400 -900);
DOT 1 (-1275 -900);
DOT 1 (-2150 -900);
DOT 1 (-125 -500);
DOT 1 (-1550 -125);
DOT 1 (3500 3000);
DOT 1 (-2150 -500);
DOT 1 (-1850 -500);
DOT 1 (-1550 -500);
DOT 1 (-1000 -500);
DOT 1 (-700 -500);
DOT 1 (-2150 250);
DOT 1 (-1550 250);
DOT 1 (-400 250);
DOT 1 (200 -500);
DOT 1 (500 -500);
DOT 1 (800 -500);
DOT 1 (1350 -500);
DOT 1 (500 250);
DOT 1 (1650 250);
DOT 1 (1950 250);
DOT 1 (3000 700);
DOT 1 (2650 1125);
DOT 1 (3000 1125);
DOT 1 (2675 1850);
DOT 1 (3400 700);
DOT 1 (3425 1850);
DOT 1 (3775 1425);
DOT 1 (3150 3000);
DOT 1 (4125 1425);
DOT 1 (4400 1425);
DOT 1 (4250 3000);
DOT 1 (4600 3000);
DOT 1 (500 3075);
DOT 1 (175 3075);
DOT 1 (-2300 3150);
DOT 1 (-1100 2725);
DOT 1 (-750 3150);
DOT 1 (-400 2725);
DOT 1 (-750 2725);
DOT 1 (-1450 3150);
DOT 1 (500 -900);
DOT 1 (800 -900);
DOT 1 (1075 -900);
DOT 1 (500 2200);
DOT 1 (-1275 -125);
DOT 1 (1950 -500);
DOT 1 (-1850 -125);
DOT 1 (200 250);
DOT 1 (-700 -125);
DOT 1 (-125 250);
DOT 1 (-1000 -125);
DOT 1 (1075 250);
DOT 1 (800 -125);
DOT 1 (200 -125);
DOT 1 (-125 -125);
DOT 1 (-400 -125);
DOT 1 (1075 -125);
DOT 1 (1650 -125);
DOT 1 (1950 -125);
DOT 1 (1350 -125);
DOT 1 (1650 -500);
DOT 1 (1950 -900);
DOT 1 (500 -125);
DOT 1 (-400 -500);
DOT 1 (1350 250);
DOT 1 (1075 -500);
DOT 1 (1900 800);
DOT 1 (1900 1300);
DOT 1 (1000 1300);
DOT 1 (1600 1300);
DOT 1 (700 800);
DOT 1 (1300 1300);
DOT 1 (100 1300);
DOT 1 (700 1300);
DOT 1 (-200 1300);
DOT 1 (3150 2450);
DOT 1 (2750 2450);
DOT 1 (3500 2450);
DOT 1 (3850 3000);
DOT 1 (2900 -400);
DOT 1 (2900 100);
DOT 1 (3200 -400);
DOT 1 (3200 100);
DOT 1 (3500 -400);
DOT 1 (3500 100);
DOT 1 (3800 -400);
DOT 1 (3800 100);
DOT 1 (3775 1850);
DOT 1 (3025 1425);
DOT 1 (-700 1625);
DOT 1 (-200 800);
DOT 1 (-500 1300);
DOT 1 (-1000 250);
FORCENOTE
TP FAB3-DVT NOPOP FROM SS BOM 20161220
(0 2400) 0;
DISPLAY LEFT (0 2400);
DISPLAY 0.638298 (0 2400);
PAINT RED (0 2400);
FORCENOTE
BOTTOM SIDE: 805
(-2254 3167) 0;
DISPLAY LEFT (-2254 3167);
DISPLAY 0.638298 (-2254 3167);
PAINT PURPLE (-2254 3167);
FORCENOTE
TP FAB3-DVT NOPOP FROM SS BOM 20161220
(-2375 2350) 0;
DISPLAY LEFT (-2375 2350);
DISPLAY 0.638298 (-2375 2350);
PAINT RED (-2375 2350);
FORCENOTE
TP FAB3-DVT CHANGE CAP 20161114
(-1550 750) 0;
DISPLAY LEFT (-1550 750);
DISPLAY 0.638298 (-1550 750);
PAINT RED (-1550 750);
FORCENOTE
TP FAB3-DVT DELETE C7W3, C7W4 ; CHANGE  C7W2 TO OSC 20161118
(-1550 700) 0;
DISPLAY LEFT (-1550 700);
DISPLAY 0.638298 (-1550 700);
PAINT RED (-1550 700);
FORCENOTE
TP FAB1 CHANGE L7A5 PN 0122
(-1600 650) 0;
DISPLAY LEFT (-1600 650);
DISPLAY 0.638298 (-1600 650);
PAINT RED (-1600 650);
FORCENOTE
TP FAB1 DELETE CAP C7A19 AND CAP C7W2-C7W13 0324
(-1600 600) 0;
DISPLAY LEFT (-1600 600);
DISPLAY 0.638298 (-1600 600);
PAINT RED (-1600 600);
FORCENOTE
PVDDQ_DEF VOLTAGE SENSE
(-1895 1530) 0;
DISPLAY LEFT (-1895 1530);
PAINT PURPLE (-1895 1530);
FORCENOTE
TP FAB1 CHANGE CAP 0311
(-2375 2400) 0;
DISPLAY LEFT (-2375 2400);
DISPLAY 0.638298 (-2375 2400);
PAINT RED (-2375 2400);
FORCENOTE
ROOM=VDDQ_DEF_CPU0
(-2350 2275) 0;
DISPLAY LEFT (-2350 2275);
DISPLAY 1.021277 (-2350 2275);
PAINT PURPLE (-2350 2275);
FORCENOTE
TP FAB1 CHANGE CAP 0322
(-1475 2525) 0;
DISPLAY LEFT (-1475 2525);
DISPLAY 1.021277 (-1475 2525);
PAINT RED (-1475 2525);
FORCENOTE
TP FAB3-DVT NOPOP FROM SS BOM 20161220
(1400 2400) 0;
DISPLAY LEFT (1400 2400);
DISPLAY 0.638298 (1400 2400);
PAINT RED (1400 2400);
FORCENOTE
TP FAB1 CHANGE CAPACITY 0322
(1400 2450) 0;
DISPLAY LEFT (1400 2450);
DISPLAY 0.638298 (1400 2450);
PAINT RED (1400 2450);
FORCENOTE
TP FAB1 CHANGE CAP 0311
(0 2450) 0;
DISPLAY LEFT (0 2450);
DISPLAY 0.638298 (0 2450);
PAINT RED (0 2450);
FORCENOTE
PVDDQ CPU CAVITY CAPS
(-1350 2425) 0;
DISPLAY LEFT (-1350 2425);
DISPLAY 1.021277 (-1350 2425);
PAINT PURPLE (-1350 2425);
FORCENOTE
TP FAB3-DVT CHANGE CAP IN SS BOM 20161220
(4175 500) 0;
DISPLAY LEFT (4175 500);
DISPLAY 0.638298 (4175 500);
PAINT RED (4175 500);
FORCENOTE
TP FAB3-DVT NOPOP FROM SS BOM 20161220
(2725 525) 0;
DISPLAY LEFT (2725 525);
DISPLAY 0.638298 (2725 525);
PAINT RED (2725 525);
FORCENOTE
CAPS TO BE PLACED BETWEEN DIMMS
(2295 3255) 0;
DISPLAY LEFT (2295 3255);
DISPLAY 1.021277 (2295 3255);
PAINT PURPLE (2295 3255);
FORCENOTE
TP FAB1 CHANGE CONNECTION 0318
(1400 2500) 0;
DISPLAY LEFT (1400 2500);
DISPLAY 0.638298 (1400 2500);
PAINT RED (1400 2500);
FORCENOTE
TOP SIDE: 603
(-1173 3167) 0;
DISPLAY LEFT (-1173 3167);
DISPLAY 0.638298 (-1173 3167);
PAINT PURPLE (-1173 3167);
FORCENOTE
TP FAB1 CHANGE CAP 0314
(300 1575) 0;
DISPLAY LEFT (300 1575);
DISPLAY 1.021277 (300 1575);
PAINT RED (300 1575);
FORCENOTE
TP FAB1 CHANGE CAP OF SINGLE SIDE 0504
(-1375 -1150) 0;
DISPLAY LEFT (-1375 -1150);
DISPLAY 1.021277 (-1375 -1150);
PAINT RED (-1375 -1150);
FORCENOTE
CAD NOTE:
(3125 -550) 0;
DISPLAY LEFT (3125 -550);
DISPLAY 1.021277 (3125 -550);
PAINT PURPLE (3125 -550);
FORCENOTE
TP FAB1 CHANGE CAP 0322
(-2375 -1150) 0;
DISPLAY LEFT (-2375 -1150);
DISPLAY 1.021277 (-2375 -1150);
PAINT RED (-2375 -1150);
FORCENOTE
ROOM = PVDDQ_DEF_PWR_VR
(-2465 -1310) 0;
DISPLAY LEFT (-2465 -1310);
DISPLAY 2.446809 (-2465 -1310);
PAINT PURPLE (-2465 -1310);
FORCENOTE
PLACE NEAR VR OUTPUT INDUCTORS
(3150 -625) 0;
DISPLAY LEFT (3150 -625);
DISPLAY 1.021277 (3150 -625);
PAINT PURPLE (3150 -625);
FORCENOTE
10MIL WIDTH
(-1145 1780) 0;
DISPLAY LEFT (-1145 1780);
DISPLAY 0.808511 (-1145 1780);
PAINT PURPLE (-1145 1780);
FORCENOTE
5MIL SPACING
(-1170 1730) 0;
DISPLAY LEFT (-1170 1730);
DISPLAY 0.808511 (-1170 1730);
PAINT PURPLE (-1170 1730);
FORCENOTE
ROUT AS DIFF PAIR
(-1220 1880) 0;
DISPLAY LEFT (-1220 1880);
DISPLAY 0.808511 (-1220 1880);
PAINT PURPLE (-1220 1880);
FORCENOTE
INPUT FILTER
(-2105 1005) 0;
DISPLAY LEFT (-2105 1005);
PAINT PURPLE (-2105 1005);
QUIT
